FILE_TYPE = MACRO_DRAWING;
SET COLOR_WIRE YELLOW;
SET COLOR_PROP ORANGE;
SET COLOR_DOT WHITE;
SET COLOR_ARC YELLOW;
SET COLOR_BODY GREEN;
SET COLOR_NOTE PURPLE;
SET PROP_DISPLAY VALUE;
SET PAGE_NUMBER P229;
FORCEADD OFFPAGE..1
(-3625 -225);
FORCEPROP 2 LAST $XR0 240 
J 0
(-3877 -225);
DISPLAY 0.638298 (-3877 -225);
PAINT MONO (-3877 -225);
FORCEPROP 2 LAST PATH I1
J 0
(-3900 -175);
DISPLAY 1.021277 (-3900 -175);
DISPLAY INVISIBLE (-3900 -175);
FORCEPROP 2 LAST CDS_LIB standard
J 0
(-3625 -225);
DISPLAY INVISIBLE (-3625 -225);
FORCEPROP 1 LAST OFFPAGE TRUE
J 0
(-3300 -350);
DISPLAY 0.872340 (-3300 -350);
PAINT GREEN (-3300 -350);
DISPLAY INVISIBLE (-3300 -350);
FORCEPROP 1 LAST COMMENT_BODY TRUE
J 0
(-3500 -325);
DISPLAY 0.872340 (-3500 -325);
PAINT PEACH (-3500 -325);
DISPLAY INVISIBLE (-3500 -325);
FORCEADD UNIVERSAL_GND..1
(-1350 -550);
FORCEPROP 3 LASTPIN (-1350 -500) SIG_NAME GND\g
J 0
(-1340 -490);
DISPLAY 0.659574 (-1340 -490);
PAINT MONO (-1340 -490);
DISPLAY INVISIBLE (-1340 -490);
FORCEPROP 1 LAST PATH I10
J 0
(-1275 -550);
DISPLAY 0.872340 (-1275 -550);
PAINT AQUA (-1275 -550);
DISPLAY INVISIBLE (-1275 -550);
FORCEPROP 2 LAST CDS_LIB logical_power
J 0
(-1350 -550);
DISPLAY INVISIBLE (-1350 -550);
FORCEPROP 1 LAST HDL_POWER GND
J 1
(-1325 -625);
DISPLAY 0.872340 (-1325 -625);
PAINT GREEN (-1325 -625);
DISPLAY INVISIBLE (-1325 -625);
FORCEADD Q_RES..2
(-675 -1825);
FORCEPROP 1 LAST PART_NUMBER CS32432FB03
J 0
(-625 -1900);
DISPLAY 0.510638 (-625 -1900);
DISPLAY INVISIBLE (-625 -1900);
FORCEPROP 2 LAST ROOM SCM_P12V_BOM2
J 0
(-625 -1725);
DISPLAY 0.510638 (-625 -1725);
FORCEPROP 1 LAST MATERIAL CHIP
J 0
(-625 -1875);
DISPLAY 0.510638 (-625 -1875);
FORCEPROP 1 LAST PACK_TYPE 0402LF
J 0
(-625 -1925);
DISPLAY 0.510638 (-625 -1925);
FORCEPROP 1 LAST VALUE 24.3K
J 0
(-625 -1800);
DISPLAY 0.510638 (-625 -1800);
FORCEPROP 1 LAST TOLERANCE 1%
J 0
(-625 -1825);
DISPLAY 0.510638 (-625 -1825);
FORCEPROP 1 LAST WATTAGE 1/16W
J 0
(-625 -1850);
DISPLAY 0.510638 (-625 -1850);
FORCEPROP 1 LAST LOCATION PR3999
J 0
(-625 -1775);
DISPLAY 0.510638 (-625 -1775);
FORCEPROP 1 LASTPIN (-675 -1725) $PN 1
J 0
(-670 -1763);
DISPLAY 0.510638 (-670 -1763);
PAINT MONO (-670 -1763);
FORCEPROP 1 LASTPIN (-675 -1925) $PN 2
J 0
(-670 -1915);
DISPLAY 0.510638 (-670 -1915);
PAINT MONO (-670 -1915);
FORCEPROP 1 LAST PATH I11
J 0
(-625 -1650);
DISPLAY 0.978723 (-625 -1650);
PAINT WHITE (-625 -1650);
DISPLAY INVISIBLE (-625 -1650);
FORCEPROP 2 LAST CDS_LIB pure_quanta
J 0
(-675 -1825);
DISPLAY INVISIBLE (-675 -1825);
FORCEPROP 0 LAST $SEC 1
J 0
(-625 -1675);
DISPLAY 0.680851 (-625 -1675);
PAINT MONO (-625 -1675);
DISPLAY INVISIBLE (-625 -1675);
FORCEPROP 0 LAST CDS_SEC 1
J 0
(-625 -1700);
DISPLAY INVISIBLE (-625 -1700);
FORCEADD Q_RES..2
(-250 -1850);
FORCEPROP 1 LAST PART_NUMBER CS32002FB06
J 0
(-200 -1925);
DISPLAY 0.510638 (-200 -1925);
DISPLAY INVISIBLE (-200 -1925);
FORCEPROP 2 LAST ROOM SCM_P12V_BOM2
J 0
(-200 -1750);
DISPLAY 0.510638 (-200 -1750);
FORCEPROP 1 LAST WATTAGE 1/16W
J 0
(-200 -1875);
DISPLAY 0.510638 (-200 -1875);
FORCEPROP 1 LAST VALUE 20K
J 0
(-200 -1825);
DISPLAY 0.510638 (-200 -1825);
FORCEPROP 1 LAST PACK_TYPE 0402LF
J 0
(-200 -1950);
DISPLAY 0.510638 (-200 -1950);
FORCEPROP 1 LAST MATERIAL CHIP
J 0
(-200 -1900);
DISPLAY 0.510638 (-200 -1900);
FORCEPROP 1 LAST TOLERANCE 1%
J 0
(-200 -1850);
DISPLAY 0.510638 (-200 -1850);
FORCEPROP 1 LAST LOCATION PR4540
J 0
(-200 -1800);
DISPLAY 0.510638 (-200 -1800);
FORCEPROP 1 LASTPIN (-250 -1750) $PN 1
J 0
(-245 -1788);
DISPLAY 0.510638 (-245 -1788);
PAINT MONO (-245 -1788);
FORCEPROP 1 LASTPIN (-250 -1950) $PN 2
J 0
(-245 -1940);
DISPLAY 0.510638 (-245 -1940);
PAINT MONO (-245 -1940);
FORCEPROP 1 LAST PATH I12
J 0
(-200 -1675);
DISPLAY 0.978723 (-200 -1675);
PAINT WHITE (-200 -1675);
DISPLAY INVISIBLE (-200 -1675);
FORCEPROP 2 LAST CDS_LIB pure_quanta
J 0
(-250 -1850);
DISPLAY INVISIBLE (-250 -1850);
FORCEPROP 0 LAST $SEC 1
J 0
(-200 -1750);
DISPLAY 0.680851 (-200 -1750);
PAINT MONO (-200 -1750);
DISPLAY INVISIBLE (-200 -1750);
FORCEPROP 0 LAST CDS_SEC 1
J 0
(-200 -1750);
DISPLAY 1.021277 (-200 -1750);
DISPLAY INVISIBLE (-200 -1750);
FORCEADD GND..1
(-175 -1500);
FORCEPROP 3 LASTPIN (-175 -1450) SIG_NAME GND\g
J 0
(-165 -1440);
DISPLAY 0.659574 (-165 -1440);
PAINT MONO (-165 -1440);
DISPLAY INVISIBLE (-165 -1440);
FORCEPROP 1 LAST PATH I13
J 0
(-100 -1500);
DISPLAY 0.872340 (-100 -1500);
PAINT AQUA (-100 -1500);
DISPLAY INVISIBLE (-100 -1500);
FORCEPROP 1 LAST SIZE 1B
J 0
(-100 -1550);
DISPLAY 0.872340 (-100 -1550);
PAINT GREEN (-100 -1550);
DISPLAY INVISIBLE (-100 -1550);
FORCEPROP 2 LAST CDS_LIB logical_power
J 0
(-175 -1500);
DISPLAY INVISIBLE (-175 -1500);
FORCEPROP 1 LAST HDL_POWER GND
J 0
(-175 -1350);
DISPLAY 0.872340 (-175 -1350);
PAINT GREEN (-175 -1350);
DISPLAY INVISIBLE (-175 -1350);
FORCEADD Q_RES..1
(-300 -1250);
FORCEPROP 1 LAST PART_NUMBER CS00002JB13
J 0
(-375 -1300);
DISPLAY 0.510638 (-375 -1300);
DISPLAY INVISIBLE (-375 -1300);
FORCEPROP 1 LAST TOLERANCE 5%
J 0
(-125 -1250);
DISPLAY 0.510638 (-125 -1250);
FORCEPROP 1 LAST PACK_TYPE 0402LF
J 0
(-50 -1250);
DISPLAY 0.510638 (-50 -1250);
FORCEPROP 2 LAST ROOM SCM_P12V_BOM2
J 0
(-350 -1150);
DISPLAY 0.510638 (-350 -1150);
FORCEPROP 1 LAST VALUE 0
J 2
(-150 -1250);
DISPLAY 0.510638 (-150 -1250);
FORCEPROP 1 LAST WATTAGE 1/16W
J 2
(-100 -1325);
DISPLAY 0.510638 (-100 -1325);
FORCEPROP 1 LAST MATERIAL CHIP
J 0
(-375 -1325);
DISPLAY 0.510638 (-375 -1325);
FORCEPROP 1 LAST $LOCATION R3998
J 0
(-350 -1200);
DISPLAY 0.510638 (-350 -1200);
FORCEPROP 1 LASTPIN (-400 -1250) $PN 1
J 0
(-388 -1238);
DISPLAY 0.510638 (-388 -1238);
PAINT MONO (-388 -1238);
FORCEPROP 1 LASTPIN (-200 -1250) $PN 2
J 0
(-238 -1238);
DISPLAY 0.510638 (-238 -1238);
PAINT MONO (-238 -1238);
FORCEPROP 1 LAST PATH I14
J 0
(-350 -1100);
DISPLAY 0.978723 (-350 -1100);
PAINT WHITE (-350 -1100);
DISPLAY INVISIBLE (-350 -1100);
FORCEPROP 2 LAST CDS_LIB pure_quanta
J 0
(-300 -1250);
DISPLAY INVISIBLE (-300 -1250);
FORCEPROP 0 LAST CDS_LOCATION R3998
J 0
(-350 -1150);
DISPLAY 1.021277 (-350 -1150);
DISPLAY INVISIBLE (-350 -1150);
FORCEPROP 0 LAST $SEC 1
J 0
(-350 -1150);
DISPLAY 0.680851 (-350 -1150);
PAINT MONO (-350 -1150);
DISPLAY INVISIBLE (-350 -1150);
FORCEPROP 0 LAST CDS_SEC 1
J 0
(-350 -1150);
DISPLAY 1.021277 (-350 -1150);
DISPLAY INVISIBLE (-350 -1150);
FORCEADD OFFPAGE..1
(-4350 875);
PAINT AQUA (-4350 875);
FORCEPROP 2 LAST $XR0 213 
J 0
(-4602 875);
DISPLAY 0.638298 (-4602 875);
PAINT MONO (-4602 875);
FORCEPROP 2 LAST PATH I15
J 0
(-4600 925);
DISPLAY 1.021277 (-4600 925);
DISPLAY INVISIBLE (-4600 925);
FORCEPROP 2 LAST CDS_LIB standard
J 0
(-4350 875);
DISPLAY INVISIBLE (-4350 875);
FORCEPROP 1 LAST OFFPAGE TRUE
J 0
(-4025 750);
DISPLAY 0.872340 (-4025 750);
PAINT AQUA (-4025 750);
DISPLAY INVISIBLE (-4025 750);
FORCEPROP 1 LAST COMMENT_BODY TRUE
J 0
(-4225 775);
DISPLAY 0.872340 (-4225 775);
PAINT GREEN (-4225 775);
DISPLAY INVISIBLE (-4225 775);
FORCEADD UNIVERSAL_POWER..1
(-3350 225);
FORCEPROP 3 LASTPIN (-3350 175) SIG_NAME P3V3_AUX\g
J 0
(-3340 185);
DISPLAY 0.659574 (-3340 185);
PAINT MONO (-3340 185);
DISPLAY INVISIBLE (-3340 185);
FORCEPROP 1 LAST HDL_POWER P3V3_AUX
J 1
(-3350 275);
DISPLAY 0.702128 (-3350 275);
PAINT GREEN (-3350 275);
FORCEPROP 1 LAST PATH I16
J 0
(-3300 250);
DISPLAY 0.872340 (-3300 250);
PAINT AQUA (-3300 250);
DISPLAY INVISIBLE (-3300 250);
FORCEPROP 2 LAST CDS_LIB logical_power
J 0
(-3350 225);
DISPLAY INVISIBLE (-3350 225);
FORCEADD Q_RES..1
(-3425 875);
FORCEPROP 1 LAST PART_NUMBER CS00002JB13
J 0
(-3675 800);
DISPLAY 0.638298 (-3675 800);
DISPLAY INVISIBLE (-3675 800);
FORCEPROP 1 LAST MATERIAL CHIP
J 0
(-3575 725);
DISPLAY 0.638298 (-3575 725);
FORCEPROP 1 LAST TOLERANCE 5%
J 0
(-3200 875);
DISPLAY 0.638298 (-3200 875);
FORCEPROP 1 LAST VALUE 0
J 2
(-3225 875);
DISPLAY 0.638298 (-3225 875);
FORCEPROP 1 LAST WATTAGE 1/16W
J 2
(-3200 725);
DISPLAY 0.638298 (-3200 725);
FORCEPROP 1 LAST PACK_TYPE 0402LF
J 0
(-3250 800);
DISPLAY 0.638298 (-3250 800);
FORCEPROP 1 LAST $LOCATION R3996
J 0
(-3475 950);
DISPLAY 0.978723 (-3475 950);
FORCEPROP 1 LASTPIN (-3525 875) $PN 1
J 0
(-3513 887);
DISPLAY 0.787234 (-3513 887);
PAINT MONO (-3513 887);
FORCEPROP 1 LASTPIN (-3325 875) $PN 2
J 0
(-3363 887);
DISPLAY 0.787234 (-3363 887);
PAINT MONO (-3363 887);
FORCEPROP 1 LAST PATH I17
J 0
(-3475 1025);
DISPLAY 0.978723 (-3475 1025);
PAINT WHITE (-3475 1025);
DISPLAY INVISIBLE (-3475 1025);
FORCEPROP 2 LAST CDS_LIB pure_quanta
J 0
(-3425 875);
DISPLAY INVISIBLE (-3425 875);
FORCEPROP 0 LAST CDS_LOCATION R3996
J 0
(-3475 975);
DISPLAY 1.021277 (-3475 975);
DISPLAY INVISIBLE (-3475 975);
FORCEPROP 0 LAST $SEC 1
J 0
(-3475 975);
DISPLAY 0.680851 (-3475 975);
PAINT MONO (-3475 975);
DISPLAY INVISIBLE (-3475 975);
FORCEPROP 0 LAST CDS_SEC 1
J 0
(-3475 975);
DISPLAY 1.021277 (-3475 975);
DISPLAY INVISIBLE (-3475 975);
FORCEADD Q_RES..2
(-3125 1150);
FORCEPROP 1 LAST PART_NUMBER CS31002FB08
J 0
(-3085 1025);
DISPLAY 0.510638 (-3085 1025);
DISPLAY INVISIBLE (-3085 1025);
FORCEPROP 1 LAST VALUE 10K
J 0
(-3080 1225);
DISPLAY 0.510638 (-3080 1225);
FORCEPROP 1 LAST MATERIAL CHIP
J 0
(-3085 1075);
DISPLAY 0.510638 (-3085 1075);
FORCEPROP 1 LAST PACK_TYPE 0402LF
J 0
(-3085 975);
DISPLAY 0.510638 (-3085 975);
FORCEPROP 1 LAST TOLERANCE 1%
J 0
(-3080 1175);
DISPLAY 0.510638 (-3080 1175);
FORCEPROP 1 LAST WATTAGE 1/16W
J 0
(-3085 1125);
DISPLAY 0.510638 (-3085 1125);
FORCEPROP 1 LAST $LOCATION R1857
J 0
(-3080 1275);
DISPLAY 0.787234 (-3080 1275);
FORCEPROP 1 LASTPIN (-3125 1250) $PN 1
J 0
(-3120 1212);
DISPLAY 0.787234 (-3120 1212);
PAINT MONO (-3120 1212);
FORCEPROP 1 LASTPIN (-3125 1050) $PN 2
J 0
(-3120 1060);
DISPLAY 0.787234 (-3120 1060);
PAINT MONO (-3120 1060);
FORCEPROP 1 LAST PATH I18
J 0
(-3075 1325);
DISPLAY 0.978723 (-3075 1325);
PAINT WHITE (-3075 1325);
DISPLAY INVISIBLE (-3075 1325);
FORCEPROP 2 LAST CDS_LIB pure_quanta
J 2
(-3125 1150);
DISPLAY INVISIBLE (-3125 1150);
FORCEPROP 0 LAST CDS_LOCATION R1857
J 0
(-3075 1325);
DISPLAY 1.021277 (-3075 1325);
DISPLAY INVISIBLE (-3075 1325);
FORCEPROP 0 LAST $SEC 1
J 0
(-3075 1325);
DISPLAY 0.680851 (-3075 1325);
PAINT MONO (-3075 1325);
DISPLAY INVISIBLE (-3075 1325);
FORCEPROP 0 LAST CDS_SEC 1
J 0
(-3075 1325);
DISPLAY 1.021277 (-3075 1325);
DISPLAY INVISIBLE (-3075 1325);
FORCEADD UNIVERSAL_POWER..1
(-3125 1400);
FORCEPROP 3 LASTPIN (-3125 1350) SIG_NAME P3V3_AUX\g
J 0
(-3115 1360);
DISPLAY 0.659574 (-3115 1360);
PAINT MONO (-3115 1360);
DISPLAY INVISIBLE (-3115 1360);
FORCEPROP 1 LAST HDL_POWER P3V3_AUX
J 1
(-3125 1450);
DISPLAY 0.702128 (-3125 1450);
PAINT GREEN (-3125 1450);
FORCEPROP 1 LAST PATH I19
J 0
(-3075 1425);
DISPLAY 0.872340 (-3075 1425);
PAINT AQUA (-3075 1425);
DISPLAY INVISIBLE (-3075 1425);
FORCEPROP 2 LAST CDS_LIB logical_power
J 0
(-3125 1400);
DISPLAY INVISIBLE (-3125 1400);
FORCEADD Q_RES..2
R 2
(-3350 0);
FORCEPROP 1 LAST PART_NUMBER CS31002FB08
J 2
(-3390 -125);
DISPLAY 0.510638 (-3390 -125);
DISPLAY INVISIBLE (-3390 -125);
FORCEPROP 1 LAST TOLERANCE 1%
J 2
(-3395 25);
DISPLAY 0.510638 (-3395 25);
FORCEPROP 1 LAST WATTAGE 1/16W
J 2
(-3390 -25);
DISPLAY 0.510638 (-3390 -25);
FORCEPROP 1 LAST PACK_TYPE 0402LF
J 2
(-3390 -175);
DISPLAY 0.510638 (-3390 -175);
FORCEPROP 1 LAST VALUE 10K
J 2
(-3395 75);
DISPLAY 0.510638 (-3395 75);
FORCEPROP 1 LAST MATERIAL CHIP
J 2
(-3390 -75);
DISPLAY 0.510638 (-3390 -75);
FORCEPROP 1 LAST $LOCATION R1854
J 2
(-3395 125);
DISPLAY 0.978723 (-3395 125);
FORCEPROP 1 LASTPIN (-3350 100) $PN 1
J 2
(-3355 62);
DISPLAY 0.787234 (-3355 62);
PAINT MONO (-3355 62);
FORCEPROP 1 LASTPIN (-3350 -100) $PN 2
J 2
(-3355 -90);
DISPLAY 0.787234 (-3355 -90);
PAINT MONO (-3355 -90);
FORCEPROP 1 LAST PATH I2
J 2
(-3400 175);
DISPLAY 0.978723 (-3400 175);
PAINT WHITE (-3400 175);
DISPLAY INVISIBLE (-3400 175);
FORCEPROP 2 LAST CDS_LIB pure_quanta
J 0
(-3350 0);
DISPLAY INVISIBLE (-3350 0);
FORCEPROP 0 LAST CDS_LOCATION R1854
J 0
(-3375 175);
DISPLAY 1.021277 (-3375 175);
DISPLAY INVISIBLE (-3375 175);
FORCEPROP 0 LAST $SEC 1
J 0
(-3375 175);
DISPLAY 0.680851 (-3375 175);
PAINT MONO (-3375 175);
DISPLAY INVISIBLE (-3375 175);
FORCEPROP 0 LAST CDS_SEC 1
J 0
(-3375 175);
DISPLAY 1.021277 (-3375 175);
DISPLAY INVISIBLE (-3375 175);
FORCEADD Q_RES..1
(-2625 875);
FORCEPROP 1 LAST PART_NUMBER CS00002JB13
J 0
(-2925 800);
DISPLAY 0.595745 (-2925 800);
DISPLAY INVISIBLE (-2925 800);
FORCEPROP 1 LAST PACK_TYPE 0402LF
J 0
(-2550 800);
DISPLAY 0.510638 (-2550 800);
FORCEPROP 1 LAST MATERIAL EMPTY
J 0
(-2750 750);
DISPLAY 0.595745 (-2750 750);
PAINT RED (-2750 750);
FORCEPROP 1 LAST WATTAGE 1/16W
J 2
(-2425 750);
DISPLAY 0.510638 (-2425 750);
FORCEPROP 1 LAST TOLERANCE 5%
J 0
(-2450 875);
DISPLAY 0.510638 (-2450 875);
FORCEPROP 1 LAST VALUE 0
J 2
(-2475 875);
DISPLAY 0.510638 (-2475 875);
FORCEPROP 2 LAST ROOM SCM_P12V_BOM1
J 0
(-2450 925);
DISPLAY 0.510638 (-2450 925);
FORCEPROP 1 LAST $LOCATION R4062
J 0
(-2775 875);
DISPLAY 0.638298 (-2775 875);
FORCEPROP 1 LAST PATH I20
J 0
(-2675 1025);
DISPLAY 0.978723 (-2675 1025);
PAINT WHITE (-2675 1025);
DISPLAY INVISIBLE (-2675 1025);
FORCEPROP 2 LAST CDS_LIB pure_quanta
J 0
(-2625 875);
DISPLAY INVISIBLE (-2625 875);
FORCEPROP 0 LAST CDS_LOCATION R4062
J 0
(-2550 950);
DISPLAY INVISIBLE (-2550 950);
FORCEPROP 0 LAST $SEC 1
J 0
(-2550 950);
DISPLAY INVISIBLE (-2550 950);
FORCEPROP 0 LAST CDS_SEC 1
J 0
(-2550 950);
DISPLAY INVISIBLE (-2550 950);
FORCEPROP 1 LASTPIN (-2725 875) $PN 1
J 0
(-2713 887);
DISPLAY 0.787234 (-2713 887);
PAINT MONO (-2713 887);
DISPLAY INVISIBLE (-2713 887);
FORCEPROP 1 LASTPIN (-2525 875) $PN 2
J 0
(-2563 887);
DISPLAY 0.787234 (-2563 887);
PAINT MONO (-2563 887);
DISPLAY INVISIBLE (-2563 887);
FORCEADD MOSFET_NCH_DUAL..1
(-1775 925);
FORCEPROP 1 LAST PART_NUMBER BAM138K0003
J 0
(-1624 839);
DISPLAY 0.510638 (-1624 839);
PAINT GREEN (-1624 839);
DISPLAY INVISIBLE (-1624 839);
FORCEPROP 1 LAST MATERIAL EMPTY
J 0
(-1624 774);
DISPLAY 0.510638 (-1624 774);
PAINT RED (-1624 774);
FORCEPROP 2 LAST ROOM SCM_P12V_BOM1
J 0
(-1600 1050);
DISPLAY 0.510638 (-1600 1050);
FORCEPROP 2 LAST PART_TYPE SMLF
J 0
(-1600 1000);
DISPLAY 0.510638 (-1600 1000);
FORCEPROP 2 LAST VALUE PJT138K
J 0
(-1600 950);
DISPLAY 0.510638 (-1600 950);
FORCEPROP 1 LAST $LOCATION Q125
J 0
(-1624 899);
DISPLAY 0.510638 (-1624 899);
PAINT GREEN (-1624 899);
FORCEPROP 0 LASTPIN (-1725 1125) $PN 6
R 1
J 0
(-1735 1135);
DISPLAY 0.510638 (-1735 1135);
PAINT MONO (-1735 1135);
FORCEPROP 0 LASTPIN (-1975 875) $PN 2
J 2
(-1985 885);
DISPLAY 0.510638 (-1985 885);
PAINT MONO (-1985 885);
FORCEPROP 0 LASTPIN (-1725 725) $PN 1
R 1
J 2
(-1735 715);
DISPLAY 0.680851 (-1735 715);
PAINT MONO (-1735 715);
FORCEPROP 1 LAST PATH I21
J 0
(-1775 925);
DISPLAY 0.723404 (-1775 925);
PAINT GREEN (-1775 925);
DISPLAY INVISIBLE (-1775 925);
FORCEPROP 1 LAST NEEDS_NO_SIZE TRUE
J 0
(-1775 924);
DISPLAY 0.468085 (-1775 924);
PAINT GREEN (-1775 924);
DISPLAY INVISIBLE (-1775 924);
FORCEPROP 1 LAST CDS_LMAN_SYM_OUTLINE -150,150,150,-150
J 0
(-1775 925);
DISPLAY 0.468085 (-1775 925);
PAINT GREEN (-1775 925);
DISPLAY INVISIBLE (-1775 925);
FORCEPROP 2 LAST CDS_LIB pure_quanta
J 0
(-1775 925);
DISPLAY INVISIBLE (-1775 925);
FORCEPROP 0 LAST CDS_LOCATION Q125
J 0
(-1600 1050);
DISPLAY 1.021277 (-1600 1050);
DISPLAY INVISIBLE (-1600 1050);
FORCEPROP 0 LAST $SEC 1
J 0
(-1600 1050);
DISPLAY 0.680851 (-1600 1050);
PAINT MONO (-1600 1050);
DISPLAY INVISIBLE (-1600 1050);
FORCEPROP 0 LAST CDS_SEC 1
J 0
(-1600 1050);
DISPLAY 1.021277 (-1600 1050);
DISPLAY INVISIBLE (-1600 1050);
FORCEADD GND..1
(-1725 575);
FORCEPROP 3 LASTPIN (-1725 625) SIG_NAME GND\g
J 0
(-1715 635);
DISPLAY 0.659574 (-1715 635);
PAINT MONO (-1715 635);
DISPLAY INVISIBLE (-1715 635);
FORCEPROP 1 LAST PATH I22
J 0
(-1650 575);
DISPLAY 0.872340 (-1650 575);
PAINT AQUA (-1650 575);
DISPLAY INVISIBLE (-1650 575);
FORCEPROP 2 LAST CDS_LIB logical_power
J 0
(-1725 575);
DISPLAY INVISIBLE (-1725 575);
FORCEPROP 1 LAST SIZE 1B
J 0
(-1650 525);
DISPLAY 0.872340 (-1650 525);
PAINT GREEN (-1650 525);
DISPLAY INVISIBLE (-1650 525);
FORCEPROP 1 LAST HDL_POWER GND
J 0
(-1725 725);
DISPLAY 0.872340 (-1725 725);
PAINT GREEN (-1725 725);
DISPLAY INVISIBLE (-1725 725);
FORCEADD GND..1
(-1050 950);
FORCEPROP 3 LASTPIN (-1050 1000) SIG_NAME GND\g
J 0
(-1040 1010);
DISPLAY 0.659574 (-1040 1010);
PAINT MONO (-1040 1010);
DISPLAY INVISIBLE (-1040 1010);
FORCEPROP 1 LAST PATH I23
J 0
(-975 950);
DISPLAY 0.872340 (-975 950);
PAINT AQUA (-975 950);
DISPLAY INVISIBLE (-975 950);
FORCEPROP 1 LAST SIZE 1B
J 0
(-975 900);
DISPLAY 0.872340 (-975 900);
PAINT GREEN (-975 900);
DISPLAY INVISIBLE (-975 900);
FORCEPROP 2 LAST CDS_LIB logical_power
J 0
(-1050 950);
DISPLAY INVISIBLE (-1050 950);
FORCEPROP 1 LAST HDL_POWER GND
J 0
(-1050 1100);
DISPLAY 0.872340 (-1050 1100);
PAINT GREEN (-1050 1100);
DISPLAY INVISIBLE (-1050 1100);
FORCEADD Q_RES..2
(-1725 1525);
FORCEPROP 1 LAST PART_NUMBER CS31002FB08
J 0
(-1670 1442);
DISPLAY 0.510638 (-1670 1442);
DISPLAY INVISIBLE (-1670 1442);
FORCEPROP 1 LAST TOLERANCE 1%
J 0
(-1665 1592);
DISPLAY 0.510638 (-1665 1592);
FORCEPROP 1 LAST WATTAGE 1/16W
J 0
(-1670 1542);
DISPLAY 0.510638 (-1670 1542);
FORCEPROP 1 LAST MATERIAL EMPTY
J 0
(-1675 1500);
DISPLAY 0.510638 (-1675 1500);
PAINT RED (-1675 1500);
FORCEPROP 1 LAST VALUE 10K
J 0
(-1665 1642);
DISPLAY 0.510638 (-1665 1642);
FORCEPROP 1 LAST PACK_TYPE 0402LF
J 0
(-1675 1375);
DISPLAY 0.510638 (-1675 1375);
FORCEPROP 2 LAST ROOM SCM_P12V_BOM1
J 0
(-1650 1725);
DISPLAY 0.510638 (-1650 1725);
FORCEPROP 1 LAST $LOCATION R4071
J 0
(-1665 1692);
DISPLAY 0.510638 (-1665 1692);
FORCEPROP 1 LASTPIN (-1725 1625) $PN 1
J 0
(-1720 1587);
DISPLAY 0.510638 (-1720 1587);
PAINT MONO (-1720 1587);
FORCEPROP 1 LASTPIN (-1725 1425) $PN 2
J 0
(-1720 1435);
DISPLAY 0.510638 (-1720 1435);
PAINT MONO (-1720 1435);
FORCEPROP 1 LAST PATH I24
J 0
(-1675 1700);
DISPLAY 0.978723 (-1675 1700);
PAINT WHITE (-1675 1700);
DISPLAY INVISIBLE (-1675 1700);
FORCEPROP 2 LAST CDS_LIB pure_quanta
J 0
(-1725 1525);
DISPLAY INVISIBLE (-1725 1525);
FORCEPROP 0 LAST CDS_LOCATION R4071
J 0
(-1675 1725);
DISPLAY 1.021277 (-1675 1725);
DISPLAY INVISIBLE (-1675 1725);
FORCEPROP 0 LAST $SEC 1
J 0
(-1675 1725);
DISPLAY 0.680851 (-1675 1725);
PAINT MONO (-1675 1725);
DISPLAY INVISIBLE (-1675 1725);
FORCEPROP 0 LAST CDS_SEC 1
J 0
(-1675 1725);
DISPLAY 1.021277 (-1675 1725);
DISPLAY INVISIBLE (-1675 1725);
FORCEADD UNIVERSAL_POWER..1
(-1725 1775);
FORCEPROP 3 LASTPIN (-1725 1725) SIG_NAME P12V_AUX\g
J 0
(-1715 1735);
DISPLAY 0.659574 (-1715 1735);
PAINT MONO (-1715 1735);
DISPLAY INVISIBLE (-1715 1735);
FORCEPROP 1 LAST HDL_POWER P12V_AUX
J 1
(-1725 1825);
DISPLAY 0.510638 (-1725 1825);
PAINT GREEN (-1725 1825);
FORCEPROP 1 LAST PATH I25
J 0
(-1675 1800);
DISPLAY 0.872340 (-1675 1800);
PAINT AQUA (-1675 1800);
DISPLAY INVISIBLE (-1675 1800);
FORCEPROP 2 LAST CDS_LIB logical_power
J 0
(-1725 1775);
DISPLAY INVISIBLE (-1725 1775);
FORCEADD MOSFET_NCH_DUAL..2
(-1100 1275);
FORCEPROP 1 LAST PART_NUMBER BAM138K0003
J 0
(-949 1181);
DISPLAY 0.510638 (-949 1181);
PAINT GREEN (-949 1181);
DISPLAY INVISIBLE (-949 1181);
FORCEPROP 2 LAST PART_TYPE SMLF
J 0
(-925 1350);
DISPLAY 0.510638 (-925 1350);
FORCEPROP 2 LAST VALUE PJT138K
J 0
(-925 1300);
DISPLAY 0.510638 (-925 1300);
FORCEPROP 2 LAST ROOM SCM_P12V_BOM1
J 0
(-925 1400);
DISPLAY 0.510638 (-925 1400);
FORCEPROP 1 LAST MATERIAL EMPTY
J 0
(-949 1126);
DISPLAY 0.510638 (-949 1126);
PAINT RED (-949 1126);
FORCEPROP 1 LAST $LOCATION Q125
J 0
(-949 1251);
DISPLAY 0.510638 (-949 1251);
PAINT GREEN (-949 1251);
FORCEPROP 0 LASTPIN (-1050 1475) $PN 3
R 1
J 0
(-1060 1485);
DISPLAY 0.510638 (-1060 1485);
PAINT MONO (-1060 1485);
FORCEPROP 0 LASTPIN (-1300 1225) $PN 5
J 2
(-1310 1235);
DISPLAY 0.510638 (-1310 1235);
PAINT MONO (-1310 1235);
FORCEPROP 0 LASTPIN (-1050 1075) $PN 4
R 1
J 2
(-1060 1065);
DISPLAY 0.510638 (-1060 1065);
PAINT MONO (-1060 1065);
FORCEPROP 1 LAST PATH I26
J 0
(-950 1125);
DISPLAY 0.723404 (-950 1125);
PAINT GREEN (-950 1125);
DISPLAY INVISIBLE (-950 1125);
FORCEPROP 2 LAST CDS_LIB pure_quanta
J 0
(-1100 1275);
DISPLAY INVISIBLE (-1100 1275);
FORCEPROP 1 LAST CDS_LMAN_SYM_OUTLINE -150,150,150,-150
J 0
(-1100 1275);
DISPLAY 0.468085 (-1100 1275);
PAINT GREEN (-1100 1275);
DISPLAY INVISIBLE (-1100 1275);
FORCEPROP 1 LAST NEEDS_NO_SIZE TRUE
J 0
(-950 1166);
DISPLAY 0.468085 (-950 1166);
PAINT GREEN (-950 1166);
DISPLAY INVISIBLE (-950 1166);
FORCEPROP 0 LAST CDS_LOCATION Q125
J 0
(-925 1400);
DISPLAY 1.021277 (-925 1400);
DISPLAY INVISIBLE (-925 1400);
FORCEPROP 0 LAST $SEC 2
J 0
(-925 1400);
DISPLAY 0.680851 (-925 1400);
PAINT MONO (-925 1400);
DISPLAY INVISIBLE (-925 1400);
FORCEPROP 0 LAST CDS_SEC 2
J 0
(-925 1400);
DISPLAY 1.021277 (-925 1400);
DISPLAY INVISIBLE (-925 1400);
FORCEADD Q_RES..1
(-500 1600);
FORCEPROP 1 LAST PART_NUMBER CS00002JB13
J 0
(-575 1550);
DISPLAY 0.510638 (-575 1550);
DISPLAY INVISIBLE (-575 1550);
FORCEPROP 1 LAST WATTAGE 1/16W
J 2
(-300 1500);
DISPLAY 0.510638 (-300 1500);
FORCEPROP 1 LAST TOLERANCE 5%
J 0
(-325 1600);
DISPLAY 0.510638 (-325 1600);
FORCEPROP 2 LAST ROOM SCM_P12V_BOM1
J 0
(-550 1700);
DISPLAY 0.510638 (-550 1700);
FORCEPROP 1 LAST MATERIAL EMPTY
J 0
(-575 1500);
DISPLAY 0.510638 (-575 1500);
PAINT RED (-575 1500);
FORCEPROP 1 LAST VALUE 0
J 2
(-350 1600);
DISPLAY 0.510638 (-350 1600);
FORCEPROP 1 LAST PACK_TYPE 0402LF
J 0
(-225 1600);
DISPLAY 0.510638 (-225 1600);
FORCEPROP 1 LAST $LOCATION R3997
J 0
(-550 1650);
DISPLAY 0.510638 (-550 1650);
FORCEPROP 1 LASTPIN (-600 1600) $PN 1
J 0
(-588 1612);
DISPLAY 0.510638 (-588 1612);
PAINT MONO (-588 1612);
FORCEPROP 1 LASTPIN (-400 1600) $PN 2
J 0
(-438 1612);
DISPLAY 0.510638 (-438 1612);
PAINT MONO (-438 1612);
FORCEPROP 1 LAST PATH I27
J 0
(-550 1750);
DISPLAY 0.978723 (-550 1750);
PAINT WHITE (-550 1750);
DISPLAY INVISIBLE (-550 1750);
FORCEPROP 2 LAST CDS_LIB pure_quanta
J 0
(-500 1600);
DISPLAY INVISIBLE (-500 1600);
FORCEPROP 0 LAST CDS_LOCATION R3997
J 0
(-550 1700);
DISPLAY 1.021277 (-550 1700);
DISPLAY INVISIBLE (-550 1700);
FORCEPROP 0 LAST $SEC 1
J 0
(-550 1700);
DISPLAY 0.680851 (-550 1700);
PAINT MONO (-550 1700);
DISPLAY INVISIBLE (-550 1700);
FORCEPROP 0 LAST CDS_SEC 1
J 0
(-550 1700);
DISPLAY 1.021277 (-550 1700);
DISPLAY INVISIBLE (-550 1700);
FORCEADD GND..1
(-500 1850);
FORCEPROP 3 LASTPIN (-500 1900) SIG_NAME GND\g
J 0
(-490 1910);
DISPLAY 0.659574 (-490 1910);
PAINT MONO (-490 1910);
DISPLAY INVISIBLE (-490 1910);
FORCEPROP 1 LAST PATH I28
J 0
(-425 1850);
DISPLAY 0.872340 (-425 1850);
PAINT AQUA (-425 1850);
DISPLAY INVISIBLE (-425 1850);
FORCEPROP 1 LAST SIZE 1B
J 0
(-425 1800);
DISPLAY 0.872340 (-425 1800);
PAINT GREEN (-425 1800);
DISPLAY INVISIBLE (-425 1800);
FORCEPROP 2 LAST CDS_LIB logical_power
J 0
(-500 1850);
DISPLAY INVISIBLE (-500 1850);
FORCEPROP 1 LAST HDL_POWER GND
J 0
(-500 2000);
DISPLAY 0.872340 (-500 2000);
PAINT GREEN (-500 2000);
DISPLAY INVISIBLE (-500 2000);
FORCEADD DIODE_TVS..1
R 1
(-650 2250);
FORCEPROP 1 LAST PART_NUMBER BCSMF14AZ01
J 0
(-595 2167);
DISPLAY 0.510638 (-595 2167);
PAINT GREEN (-595 2167);
DISPLAY INVISIBLE (-595 2167);
FORCEPROP 1 LAST MATERIAL IC
J 0
(-600 2100);
DISPLAY 0.510638 (-600 2100);
PAINT GREEN (-600 2100);
FORCEPROP 2 LAST VALUE SMF14A
J 0
(-600 2225);
DISPLAY 0.510638 (-600 2225);
PAINT SKYBLUE (-600 2225);
FORCEPROP 1 LAST LOCATION PD115
J 0
(-595 2292);
DISPLAY 0.510638 (-595 2292);
PAINT GREEN (-595 2292);
FORCEPROP 0 LASTPIN (-650 2100) $PN A
R 1
J 2
(-660 2090);
DISPLAY 0.510638 (-660 2090);
FORCEPROP 0 LASTPIN (-650 2400) $PN C
R 1
J 0
(-660 2410);
DISPLAY 0.510638 (-660 2410);
FORCEPROP 1 LAST PATH I29
R 1
J 0
(-600 2350);
DISPLAY 0.723404 (-600 2350);
PAINT GREEN (-600 2350);
DISPLAY INVISIBLE (-600 2350);
FORCEPROP 1 LAST PIN_NAMES_ROTATE TRUE
R 1
J 0
(-650 2250);
DISPLAY 0.489362 (-650 2250);
PAINT GREEN (-650 2250);
DISPLAY INVISIBLE (-650 2250);
FORCEPROP 2 LAST CDS_LIB pure_quanta
J 0
(-650 2250);
DISPLAY INVISIBLE (-650 2250);
FORCEPROP 1 LAST CDS_LMAN_SYM_OUTLINE -100,50,100,-50
R 1
J 0
(-650 2250);
DISPLAY 0.468085 (-650 2250);
PAINT GREEN (-650 2250);
DISPLAY INVISIBLE (-650 2250);
FORCEPROP 0 LAST PART_TYPE SMLF
J 0
(-550 2375);
DISPLAY 1.021277 (-550 2375);
DISPLAY INVISIBLE (-550 2375);
FORCEPROP 1 LASTPIN (-650 2400) Pin_Length SHORT
R 1
J 0
(-640 2425);
DISPLAY 0.489362 (-640 2425);
PAINT MONO (-640 2425);
DISPLAY INVISIBLE (-640 2425);
FORCEPROP 0 LAST $SEC 1
R 1
J 0
(-595 2342);
DISPLAY INVISIBLE (-595 2342);
FORCEPROP 0 LAST CDS_SEC 1
R 1
J 0
(-595 2342);
DISPLAY INVISIBLE (-595 2342);
FORCEADD Q_RES..1
(-2400 -225);
FORCEPROP 1 LAST PART_NUMBER CS11002FB07
J 0
(-2600 -125);
DISPLAY 0.510638 (-2600 -125);
DISPLAY INVISIBLE (-2600 -125);
FORCEPROP 1 LAST TOLERANCE 1%
J 0
(-2200 -225);
DISPLAY 0.510638 (-2200 -225);
FORCEPROP 1 LAST WATTAGE 1/16W
J 2
(-2175 -75);
DISPLAY 0.510638 (-2175 -75);
FORCEPROP 1 LAST MATERIAL CHIP
J 0
(-2425 -75);
DISPLAY 0.510638 (-2425 -75);
FORCEPROP 1 LAST PACK_TYPE 0402LF
J 0
(-2600 -75);
DISPLAY 0.510638 (-2600 -75);
FORCEPROP 1 LAST VALUE 100
J 2
(-2225 -225);
DISPLAY 0.510638 (-2225 -225);
FORCEPROP 1 LAST $LOCATION R1856
J 0
(-2625 -225);
DISPLAY 0.638298 (-2625 -225);
FORCEPROP 1 LASTPIN (-2500 -225) $PN 1
J 0
(-2488 -213);
DISPLAY 0.787234 (-2488 -213);
PAINT MONO (-2488 -213);
FORCEPROP 1 LASTPIN (-2300 -225) $PN 2
J 0
(-2338 -213);
DISPLAY 0.787234 (-2338 -213);
PAINT MONO (-2338 -213);
FORCEPROP 1 LAST PATH I3
J 0
(-2450 -75);
DISPLAY 0.978723 (-2450 -75);
PAINT WHITE (-2450 -75);
DISPLAY INVISIBLE (-2450 -75);
FORCEPROP 2 LAST CDS_LIB pure_quanta
J 0
(-2400 -225);
DISPLAY INVISIBLE (-2400 -225);
FORCEPROP 0 LAST CDS_LOCATION R1856
J 0
(-2175 -50);
DISPLAY 1.021277 (-2175 -50);
DISPLAY INVISIBLE (-2175 -50);
FORCEPROP 0 LAST $SEC 1
J 0
(-2175 -50);
DISPLAY 0.680851 (-2175 -50);
PAINT MONO (-2175 -50);
DISPLAY INVISIBLE (-2175 -50);
FORCEPROP 0 LAST CDS_SEC 1
J 0
(-2175 -50);
DISPLAY 1.021277 (-2175 -50);
DISPLAY INVISIBLE (-2175 -50);
FORCEADD UNIVERSAL_POWER..1
(-500 2575);
FORCEPROP 3 LASTPIN (-500 2525) SIG_NAME P12V_AUX\g
J 0
(-490 2535);
DISPLAY 0.659574 (-490 2535);
PAINT MONO (-490 2535);
DISPLAY INVISIBLE (-490 2535);
FORCEPROP 1 LAST HDL_POWER P12V_AUX
J 1
(-500 2625);
DISPLAY 0.510638 (-500 2625);
PAINT GREEN (-500 2625);
FORCEPROP 1 LAST PATH I30
J 0
(-450 2600);
DISPLAY 0.872340 (-450 2600);
PAINT AQUA (-450 2600);
DISPLAY INVISIBLE (-450 2600);
FORCEPROP 2 LAST CDS_LIB logical_power
J 0
(-500 2575);
DISPLAY INVISIBLE (-500 2575);
FORCEADD Q_CAP..1
(-275 2225);
FORCEPROP 1 LAST PART_NUMBER CH5104KEB02
J 0
(-225 2175);
DISPLAY 0.510638 (-225 2175);
DISPLAY INVISIBLE (-225 2175);
FORCEPROP 1 LAST MATERIAL X6S
J 0
(-225 2225);
DISPLAY 0.510638 (-225 2225);
FORCEPROP 1 LAST VOLTAGE 25V
J 0
(-225 2250);
DISPLAY 0.510638 (-225 2250);
FORCEPROP 1 LAST VALUE 1UF
J 0
(-225 2275);
DISPLAY 0.510638 (-225 2275);
FORCEPROP 1 LAST PACK_TYPE C0402
J 0
(-225 2200);
DISPLAY 0.510638 (-225 2200);
FORCEPROP 1 LAST LOCATION PC2230
J 0
(-225 2300);
DISPLAY 0.510638 (-225 2300);
FORCEPROP 1 LAST PATH I31
J 0
(-225 2375);
DISPLAY 0.978723 (-225 2375);
PAINT WHITE (-225 2375);
DISPLAY INVISIBLE (-225 2375);
FORCEPROP 2 LAST CDS_LIB pure_quanta
J 0
(-275 2225);
DISPLAY INVISIBLE (-275 2225);
FORCEPROP 1 LAST TOLERANCE 10%
J 0
(-225 2175);
DISPLAY 0.638298 (-225 2175);
DISPLAY INVISIBLE (-225 2175);
FORCEPROP 0 LAST $SEC 1
J 0
(-220 2367);
DISPLAY INVISIBLE (-220 2367);
FORCEPROP 0 LAST CDS_SEC 1
J 0
(-220 2367);
DISPLAY INVISIBLE (-220 2367);
FORCEPROP 1 LASTPIN (-275 2325) $PN 1
J 0
(-265 2305);
DISPLAY 0.787234 (-265 2305);
PAINT MONO (-265 2305);
DISPLAY INVISIBLE (-265 2305);
FORCEPROP 1 LASTPIN (-275 2125) $PN 2
J 0
(-265 2105);
DISPLAY 0.787234 (-265 2105);
PAINT MONO (-265 2105);
DISPLAY INVISIBLE (-265 2105);
FORCEADD GND..1
(225 -2150);
FORCEPROP 3 LASTPIN (225 -2100) SIG_NAME GND\g
J 0
(235 -2090);
DISPLAY 0.659574 (235 -2090);
PAINT MONO (235 -2090);
DISPLAY INVISIBLE (235 -2090);
FORCEPROP 1 LAST PATH I32
J 0
(300 -2150);
DISPLAY 0.872340 (300 -2150);
PAINT AQUA (300 -2150);
DISPLAY INVISIBLE (300 -2150);
FORCEPROP 2 LAST CDS_LIB logical_power
J 0
(225 -2150);
DISPLAY INVISIBLE (225 -2150);
FORCEPROP 1 LAST SIZE 1B
J 0
(300 -2200);
DISPLAY 0.872340 (300 -2200);
PAINT GREEN (300 -2200);
DISPLAY INVISIBLE (300 -2200);
FORCEPROP 1 LAST HDL_POWER GND
J 0
(225 -2000);
DISPLAY 0.872340 (225 -2000);
PAINT GREEN (225 -2000);
DISPLAY INVISIBLE (225 -2000);
FORCEADD Q_CAP..1
(225 -1925);
FORCEPROP 1 LAST PART_NUMBER CH3474K1B04
J 0
(275 -1975);
DISPLAY 0.510638 (275 -1975);
DISPLAY INVISIBLE (275 -1975);
FORCEPROP 1 LAST MATERIAL X7R
J 0
(275 -1950);
DISPLAY 0.510638 (275 -1950);
FORCEPROP 1 LAST VOLTAGE 25V
J 0
(275 -1925);
DISPLAY 0.510638 (275 -1925);
FORCEPROP 1 LAST VALUE 0.047UF
J 0
(275 -1900);
DISPLAY 0.510638 (275 -1900);
FORCEPROP 1 LAST PACK_TYPE C0402
J 0
(275 -2000);
DISPLAY 0.510638 (275 -2000);
FORCEPROP 2 LAST ROOM SCM_P12V_BOM2
J 0
(275 -1825);
DISPLAY 0.510638 (275 -1825);
FORCEPROP 1 LAST LOCATION PC2232
J 0
(275 -1875);
DISPLAY 0.510638 (275 -1875);
FORCEPROP 1 LAST PATH I33
J 0
(275 -1775);
DISPLAY 0.978723 (275 -1775);
PAINT WHITE (275 -1775);
DISPLAY INVISIBLE (275 -1775);
FORCEPROP 1 LAST TOLERANCE 10%
J 0
(275 -1975);
DISPLAY 0.638298 (275 -1975);
DISPLAY INVISIBLE (275 -1975);
FORCEPROP 2 LAST CDS_LIB pure_quanta
J 0
(225 -1925);
DISPLAY INVISIBLE (225 -1925);
FORCEPROP 0 LAST $SEC 1
J 0
(275 -1775);
DISPLAY INVISIBLE (275 -1775);
FORCEPROP 0 LAST CDS_SEC 1
J 0
(275 -1775);
DISPLAY INVISIBLE (275 -1775);
FORCEPROP 1 LASTPIN (225 -1825) $PN 1
J 0
(235 -1845);
DISPLAY 0.787234 (235 -1845);
PAINT MONO (235 -1845);
DISPLAY INVISIBLE (235 -1845);
FORCEPROP 1 LASTPIN (225 -2025) $PN 2
J 0
(235 -2045);
DISPLAY 0.787234 (235 -2045);
PAINT MONO (235 -2045);
DISPLAY INVISIBLE (235 -2045);
FORCEADD Q_RES..2
(1650 -2125);
FORCEPROP 1 LAST PART_NUMBER CS33012FB03
J 0
(1700 -2200);
DISPLAY 0.510638 (1700 -2200);
DISPLAY INVISIBLE (1700 -2200);
FORCEPROP 1 LAST VALUE 30.1K
J 0
(1700 -2100);
DISPLAY 0.510638 (1700 -2100);
FORCEPROP 1 LAST TOLERANCE 1%
J 0
(1700 -2125);
DISPLAY 0.510638 (1700 -2125);
FORCEPROP 1 LAST WATTAGE 1/16W
J 0
(1700 -2150);
DISPLAY 0.510638 (1700 -2150);
FORCEPROP 1 LAST MATERIAL CHIP
J 0
(1700 -2175);
DISPLAY 0.510638 (1700 -2175);
FORCEPROP 1 LAST PACK_TYPE 0402LF
J 0
(1700 -2225);
DISPLAY 0.510638 (1700 -2225);
FORCEPROP 2 LAST ROOM SCM_P12V_BOM2
J 0
(1700 -2025);
DISPLAY 0.510638 (1700 -2025);
FORCEPROP 1 LAST LOCATION PR4005
J 0
(1700 -2075);
DISPLAY 0.510638 (1700 -2075);
FORCEPROP 1 LASTPIN (1650 -2025) $PN 1
J 0
(1655 -2063);
DISPLAY 0.510638 (1655 -2063);
PAINT MONO (1655 -2063);
FORCEPROP 1 LASTPIN (1650 -2225) $PN 2
J 0
(1655 -2215);
DISPLAY 0.510638 (1655 -2215);
PAINT MONO (1655 -2215);
FORCEPROP 1 LAST PATH I34
J 0
(1700 -1950);
DISPLAY 0.978723 (1700 -1950);
PAINT WHITE (1700 -1950);
DISPLAY INVISIBLE (1700 -1950);
FORCEPROP 2 LAST CDS_LIB pure_quanta
J 0
(1650 -2125);
DISPLAY INVISIBLE (1650 -2125);
FORCEPROP 0 LAST $SEC 1
J 0
(1700 -1950);
DISPLAY 0.680851 (1700 -1950);
PAINT MONO (1700 -1950);
DISPLAY INVISIBLE (1700 -1950);
FORCEPROP 0 LAST CDS_SEC 1
J 0
(1700 -1950);
DISPLAY 1.021277 (1700 -1950);
DISPLAY INVISIBLE (1700 -1950);
FORCEADD GND..1
(150 -1075);
FORCEPROP 3 LASTPIN (150 -1025) SIG_NAME GND\g
J 0
(160 -1015);
DISPLAY 0.659574 (160 -1015);
PAINT MONO (160 -1015);
DISPLAY INVISIBLE (160 -1015);
FORCEPROP 1 LAST PATH I35
J 0
(225 -1075);
DISPLAY 0.872340 (225 -1075);
PAINT AQUA (225 -1075);
DISPLAY INVISIBLE (225 -1075);
FORCEPROP 2 LAST CDS_LIB logical_power
J 0
(150 -1075);
DISPLAY INVISIBLE (150 -1075);
FORCEPROP 1 LAST SIZE 1B
J 0
(225 -1125);
DISPLAY 0.872340 (225 -1125);
PAINT GREEN (225 -1125);
DISPLAY INVISIBLE (225 -1125);
FORCEPROP 1 LAST HDL_POWER GND
J 0
(150 -925);
DISPLAY 0.872340 (150 -925);
PAINT GREEN (150 -925);
DISPLAY INVISIBLE (150 -925);
FORCEADD GND..1
(566 -1984);
FORCEPROP 3 LASTPIN (566 -1934) SIG_NAME GND\g
J 0
(576 -1924);
DISPLAY 0.659574 (576 -1924);
PAINT MONO (576 -1924);
DISPLAY INVISIBLE (576 -1924);
FORCEPROP 1 LAST PATH I36
J 0
(641 -1984);
DISPLAY 0.872340 (641 -1984);
PAINT AQUA (641 -1984);
DISPLAY INVISIBLE (641 -1984);
FORCEPROP 1 LAST SIZE 1B
J 0
(641 -2034);
DISPLAY 0.872340 (641 -2034);
PAINT GREEN (641 -2034);
DISPLAY INVISIBLE (641 -2034);
FORCEPROP 2 LAST CDS_LIB logical_power
J 0
(566 -1984);
DISPLAY INVISIBLE (566 -1984);
FORCEPROP 1 LAST HDL_POWER GND
J 0
(566 -1834);
DISPLAY 0.872340 (566 -1834);
PAINT GREEN (566 -1834);
DISPLAY INVISIBLE (566 -1834);
FORCEADD Q_CAP..1
(150 -850);
FORCEPROP 1 LAST PART_NUMBER CH5104KEB02
J 0
(200 -900);
DISPLAY 0.510638 (200 -900);
DISPLAY INVISIBLE (200 -900);
FORCEPROP 2 LAST ROOM SCM_P12V_BOM2
J 0
(200 -750);
DISPLAY 0.510638 (200 -750);
FORCEPROP 1 LAST VOLTAGE 25V
J 0
(200 -850);
DISPLAY 0.510638 (200 -850);
FORCEPROP 1 LAST VALUE 1UF
J 0
(200 -825);
DISPLAY 0.510638 (200 -825);
FORCEPROP 1 LAST PACK_TYPE C0402
J 0
(200 -925);
DISPLAY 0.510638 (200 -925);
FORCEPROP 1 LAST MATERIAL X6S
J 0
(200 -875);
DISPLAY 0.510638 (200 -875);
FORCEPROP 1 LAST LOCATION PC2231
J 0
(200 -800);
DISPLAY 0.510638 (200 -800);
FORCEPROP 1 LAST PATH I37
J 0
(200 -700);
DISPLAY 0.978723 (200 -700);
PAINT WHITE (200 -700);
DISPLAY INVISIBLE (200 -700);
FORCEPROP 1 LAST TOLERANCE 10%
J 0
(200 -900);
DISPLAY 0.638298 (200 -900);
DISPLAY INVISIBLE (200 -900);
FORCEPROP 2 LAST CDS_LIB pure_quanta
J 0
(150 -850);
DISPLAY INVISIBLE (150 -850);
FORCEPROP 0 LAST $SEC 1
J 0
(205 -708);
DISPLAY INVISIBLE (205 -708);
FORCEPROP 0 LAST CDS_SEC 1
J 0
(205 -708);
DISPLAY INVISIBLE (205 -708);
FORCEPROP 1 LASTPIN (150 -750) $PN 1
J 0
(160 -770);
DISPLAY 0.787234 (160 -770);
PAINT MONO (160 -770);
DISPLAY INVISIBLE (160 -770);
FORCEPROP 1 LASTPIN (150 -950) $PN 2
J 0
(160 -970);
DISPLAY 0.787234 (160 -970);
PAINT MONO (160 -970);
DISPLAY INVISIBLE (160 -970);
FORCEADD UNIVERSAL_POWER..1
(150 -500);
FORCEPROP 3 LASTPIN (150 -550) SIG_NAME P12V_AUX\g
J 0
(160 -540);
DISPLAY 0.659574 (160 -540);
PAINT MONO (160 -540);
DISPLAY INVISIBLE (160 -540);
FORCEPROP 1 LAST HDL_POWER P12V_AUX
J 1
(150 -450);
DISPLAY 0.872340 (150 -450);
PAINT GREEN (150 -450);
FORCEPROP 1 LAST PATH I38
J 0
(200 -475);
DISPLAY 0.872340 (200 -475);
PAINT AQUA (200 -475);
DISPLAY INVISIBLE (200 -475);
FORCEPROP 2 LAST CDS_LIB logical_power
J 0
(150 -500);
DISPLAY INVISIBLE (150 -500);
FORCEADD Q_RES..2
(2025 -1275);
FORCEPROP 1 LAST PART_NUMBER CS11002FB07
J 0
(2075 -1325);
DISPLAY 0.510638 (2075 -1325);
DISPLAY INVISIBLE (2075 -1325);
FORCEPROP 1 LAST MATERIAL EMPTY
J 0
(2075 -1300);
DISPLAY 0.510638 (2075 -1300);
PAINT RED (2075 -1300);
FORCEPROP 1 LAST PACK_TYPE 0402LF
J 0
(2075 -1350);
DISPLAY 0.510638 (2075 -1350);
FORCEPROP 1 LAST VALUE 100
J 0
(2070 -1225);
DISPLAY 0.510638 (2070 -1225);
FORCEPROP 1 LAST TOLERANCE 1%
J 0
(2075 -1250);
DISPLAY 0.510638 (2075 -1250);
FORCEPROP 1 LAST WATTAGE 1/16W
J 0
(2075 -1275);
DISPLAY 0.510638 (2075 -1275);
FORCEPROP 1 LAST LOCATION PR4006
J 0
(2075 -1200);
DISPLAY 0.510638 (2075 -1200);
FORCEPROP 1 LASTPIN (2025 -1175) $PN 1
J 0
(2030 -1213);
DISPLAY 0.510638 (2030 -1213);
PAINT MONO (2030 -1213);
FORCEPROP 1 LASTPIN (2025 -1375) $PN 2
J 0
(2030 -1365);
DISPLAY 0.510638 (2030 -1365);
PAINT MONO (2030 -1365);
FORCEPROP 1 LAST PATH I39
J 0
(2075 -1100);
DISPLAY 0.978723 (2075 -1100);
PAINT WHITE (2075 -1100);
DISPLAY INVISIBLE (2075 -1100);
FORCEPROP 2 LAST CDS_LIB pure_quanta
J 0
(2025 -1275);
DISPLAY INVISIBLE (2025 -1275);
FORCEPROP 0 LAST $SEC 1
J 0
(2075 -1100);
DISPLAY 0.680851 (2075 -1100);
PAINT MONO (2075 -1100);
DISPLAY INVISIBLE (2075 -1100);
FORCEPROP 0 LAST CDS_SEC 1
J 0
(2075 -1100);
DISPLAY 1.021277 (2075 -1100);
DISPLAY INVISIBLE (2075 -1100);
FORCEADD GND..1
(-1125 -2050);
FORCEPROP 3 LASTPIN (-1125 -2000) SIG_NAME GND\g
J 0
(-1115 -1990);
DISPLAY 0.659574 (-1115 -1990);
PAINT MONO (-1115 -1990);
DISPLAY INVISIBLE (-1115 -1990);
FORCEPROP 1 LAST PATH I4
J 0
(-1050 -2050);
DISPLAY 0.872340 (-1050 -2050);
PAINT AQUA (-1050 -2050);
DISPLAY INVISIBLE (-1050 -2050);
FORCEPROP 2 LAST CDS_LIB logical_power
J 0
(-1125 -2050);
DISPLAY INVISIBLE (-1125 -2050);
FORCEPROP 1 LAST SIZE 1B
J 0
(-1050 -2100);
DISPLAY 0.872340 (-1050 -2100);
PAINT GREEN (-1050 -2100);
DISPLAY INVISIBLE (-1050 -2100);
FORCEPROP 1 LAST HDL_POWER GND
J 0
(-1125 -1900);
DISPLAY 0.872340 (-1125 -1900);
PAINT GREEN (-1125 -1900);
DISPLAY INVISIBLE (-1125 -1900);
FORCEADD Q_CAP..1
(2100 -2125);
FORCEPROP 1 LAST PART_NUMBER CH4106K1B01
J 0
(2175 -2175);
DISPLAY 0.510638 (2175 -2175);
DISPLAY INVISIBLE (2175 -2175);
FORCEPROP 2 LAST ROOM SCM_P12V_BOM2
J 0
(2175 -2025);
DISPLAY 0.510638 (2175 -2025);
FORCEPROP 1 LAST VOLTAGE 50V
J 0
(2175 -2125);
DISPLAY 0.510638 (2175 -2125);
FORCEPROP 1 LAST PACK_TYPE C0402
J 0
(2175 -2200);
DISPLAY 0.510638 (2175 -2200);
FORCEPROP 1 LAST MATERIAL X7R
J 0
(2175 -2150);
DISPLAY 0.510638 (2175 -2150);
FORCEPROP 1 LAST VALUE 100NF
J 0
(2175 -2100);
DISPLAY 0.510638 (2175 -2100);
FORCEPROP 1 LAST LOCATION PC2235
J 0
(2175 -2075);
DISPLAY 0.510638 (2175 -2075);
FORCEPROP 1 LAST PATH I42
J 0
(2150 -1975);
DISPLAY 0.978723 (2150 -1975);
PAINT WHITE (2150 -1975);
DISPLAY INVISIBLE (2150 -1975);
FORCEPROP 1 LAST TOLERANCE 10%
J 0
(2150 -2175);
DISPLAY 0.638298 (2150 -2175);
DISPLAY INVISIBLE (2150 -2175);
FORCEPROP 2 LAST CDS_LIB pure_quanta
J 0
(2100 -2125);
DISPLAY INVISIBLE (2100 -2125);
FORCEPROP 0 LAST $SEC 1
J 0
(2150 -1975);
DISPLAY INVISIBLE (2150 -1975);
FORCEPROP 0 LAST CDS_SEC 1
J 0
(2150 -1975);
DISPLAY INVISIBLE (2150 -1975);
FORCEPROP 1 LASTPIN (2100 -2025) $PN 1
J 0
(2110 -2045);
DISPLAY 0.787234 (2110 -2045);
PAINT MONO (2110 -2045);
DISPLAY INVISIBLE (2110 -2045);
FORCEPROP 1 LASTPIN (2100 -2225) $PN 2
J 0
(2110 -2245);
DISPLAY 0.787234 (2110 -2245);
PAINT MONO (2110 -2245);
DISPLAY INVISIBLE (2110 -2245);
FORCEADD GND..1
(2100 -2525);
FORCEPROP 3 LASTPIN (2100 -2475) SIG_NAME GND\g
J 0
(2110 -2465);
DISPLAY 0.659574 (2110 -2465);
PAINT MONO (2110 -2465);
DISPLAY INVISIBLE (2110 -2465);
FORCEPROP 1 LAST PATH I43
J 0
(2175 -2525);
DISPLAY 0.872340 (2175 -2525);
PAINT AQUA (2175 -2525);
DISPLAY INVISIBLE (2175 -2525);
FORCEPROP 1 LAST SIZE 1B
J 0
(2175 -2575);
DISPLAY 0.872340 (2175 -2575);
PAINT GREEN (2175 -2575);
DISPLAY INVISIBLE (2175 -2575);
FORCEPROP 2 LAST CDS_LIB logical_power
J 0
(2100 -2525);
DISPLAY INVISIBLE (2100 -2525);
FORCEPROP 1 LAST HDL_POWER GND
J 0
(2100 -2375);
DISPLAY 0.872340 (2100 -2375);
PAINT GREEN (2100 -2375);
DISPLAY INVISIBLE (2100 -2375);
FORCEADD Q_RES..1
(2700 -2300);
FORCEPROP 1 LAST PART_NUMBER CS00002JB13
J 0
(2525 -2350);
DISPLAY 0.595745 (2525 -2350);
DISPLAY INVISIBLE (2525 -2350);
FORCEPROP 1 LAST MATERIAL CHIP
J 0
(2475 -2300);
DISPLAY 0.595745 (2475 -2300);
FORCEPROP 2 LAST ROOM SCM_P12V_BOM2
J 0
(2525 -2375);
DISPLAY 0.510638 (2525 -2375);
FORCEPROP 1 LAST VALUE 0
J 2
(2850 -2300);
DISPLAY 0.595745 (2850 -2300);
FORCEPROP 1 LAST TOLERANCE 5%
J 0
(2875 -2300);
DISPLAY 0.595745 (2875 -2300);
FORCEPROP 1 LAST WATTAGE 1/16W
J 2
(2500 -2350);
DISPLAY 0.595745 (2500 -2350);
FORCEPROP 1 LAST PACK_TYPE 0402LF
J 0
(2850 -2350);
DISPLAY 0.595745 (2850 -2350);
FORCEPROP 1 LAST $LOCATION R4709
J 0
(2350 -2300);
DISPLAY 0.638298 (2350 -2300);
FORCEPROP 1 LASTPIN (2600 -2300) $PN 1
J 0
(2612 -2288);
DISPLAY 0.787234 (2612 -2288);
PAINT MONO (2612 -2288);
FORCEPROP 1 LASTPIN (2800 -2300) $PN 2
J 0
(2762 -2288);
DISPLAY 0.787234 (2762 -2288);
PAINT MONO (2762 -2288);
FORCEPROP 1 LAST PATH I44
J 0
(2650 -2150);
DISPLAY 0.978723 (2650 -2150);
PAINT WHITE (2650 -2150);
DISPLAY INVISIBLE (2650 -2150);
FORCEPROP 2 LAST CDS_LIB pure_quanta
J 0
(2700 -2300);
DISPLAY INVISIBLE (2700 -2300);
FORCEPROP 0 LAST CDS_LOCATION R4709
J 0
(2875 -2250);
DISPLAY 1.021277 (2875 -2250);
DISPLAY INVISIBLE (2875 -2250);
FORCEPROP 0 LAST $SEC 1
J 0
(2875 -2250);
DISPLAY 0.680851 (2875 -2250);
PAINT MONO (2875 -2250);
DISPLAY INVISIBLE (2875 -2250);
FORCEPROP 0 LAST CDS_SEC 1
J 0
(2875 -2250);
DISPLAY 1.021277 (2875 -2250);
DISPLAY INVISIBLE (2875 -2250);
FORCEADD GND..1
(3225 -2100);
FORCEPROP 3 LASTPIN (3225 -2050) SIG_NAME GND\g
J 0
(3235 -2040);
DISPLAY 0.659574 (3235 -2040);
PAINT MONO (3235 -2040);
DISPLAY INVISIBLE (3235 -2040);
FORCEPROP 1 LAST PATH I45
J 0
(3300 -2100);
DISPLAY 0.872340 (3300 -2100);
PAINT AQUA (3300 -2100);
DISPLAY INVISIBLE (3300 -2100);
FORCEPROP 1 LAST SIZE 1B
J 0
(3300 -2150);
DISPLAY 0.872340 (3300 -2150);
PAINT GREEN (3300 -2150);
DISPLAY INVISIBLE (3300 -2150);
FORCEPROP 2 LAST CDS_LIB logical_power
J 0
(3225 -2100);
DISPLAY INVISIBLE (3225 -2100);
FORCEPROP 1 LAST HDL_POWER GND
J 0
(3225 -1950);
DISPLAY 0.872340 (3225 -1950);
PAINT GREEN (3225 -1950);
DISPLAY INVISIBLE (3225 -1950);
FORCEADD OFFPAGE..2
(3550 -2300);
PAINT AQUA (3550 -2300);
FORCEPROP 2 LAST $XR1 255 
J 0
(3859 -2300);
DISPLAY 0.638298 (3859 -2300);
PAINT MONO (3859 -2300);
FORCEPROP 2 LAST $XR0 242 
J 0
(3739 -2300);
DISPLAY 0.638298 (3739 -2300);
PAINT MONO (3739 -2300);
FORCEPROP 2 LAST PATH I46
J 0
(3875 -2250);
DISPLAY 1.021277 (3875 -2250);
DISPLAY INVISIBLE (3875 -2250);
FORCEPROP 1 LAST OFFPAGE TRUE
J 0
(3875 -2425);
DISPLAY 0.872340 (3875 -2425);
PAINT AQUA (3875 -2425);
DISPLAY INVISIBLE (3875 -2425);
FORCEPROP 1 LAST COMMENT_BODY TRUE
J 0
(3505 -2395);
DISPLAY 0.872340 (3505 -2395);
PAINT GREEN (3505 -2395);
DISPLAY INVISIBLE (3505 -2395);
FORCEPROP 2 LAST CDS_LIB standard
J 0
(3550 -2300);
DISPLAY INVISIBLE (3550 -2300);
FORCEADD OFFPAGE..1
R 2
(2225 -1500);
PAINT AQUA (2225 -1500);
FORCEPROP 2 LAST $XR0 242 
J 0
(2411 -1500);
DISPLAY 0.638298 (2411 -1500);
PAINT MONO (2411 -1500);
FORCEPROP 2 LAST PATH I47
J 0
(2425 -1475);
DISPLAY 1.021277 (2425 -1475);
DISPLAY INVISIBLE (2425 -1475);
FORCEPROP 2 LAST CDS_LIB standard
J 2
(2225 -1500);
DISPLAY INVISIBLE (2225 -1500);
FORCEPROP 1 LAST OFFPAGE TRUE
J 2
(1900 -1625);
DISPLAY 0.872340 (1900 -1625);
PAINT AQUA (1900 -1625);
DISPLAY INVISIBLE (1900 -1625);
FORCEPROP 1 LAST COMMENT_BODY TRUE
J 2
(2100 -1600);
DISPLAY 0.872340 (2100 -1600);
PAINT GREEN (2100 -1600);
DISPLAY INVISIBLE (2100 -1600);
FORCEADD Q_RES..1
(2475 -1750);
FORCEPROP 1 LAST PART_NUMBER CS31002FB08
J 0
(2375 -1725);
DISPLAY 0.404255 (2375 -1725);
DISPLAY INVISIBLE (2375 -1725);
FORCEPROP 2 LAST ROOM SCM_P12V_BOM2
J 0
(2400 -1650);
DISPLAY 0.510638 (2400 -1650);
FORCEPROP 1 LAST MATERIAL CHIP
J 0
(2600 -1775);
DISPLAY 0.404255 (2600 -1775);
PAINT RED (2600 -1775);
FORCEPROP 1 LAST WATTAGE 1/16W
J 2
(2800 -1775);
DISPLAY 0.404255 (2800 -1775);
FORCEPROP 1 LAST TOLERANCE 1%
J 0
(2525 -1775);
DISPLAY 0.510638 (2525 -1775);
FORCEPROP 1 LAST VALUE 10K
J 2
(2450 -1775);
DISPLAY 0.510638 (2450 -1775);
FORCEPROP 1 LAST PACK_TYPE 0402LF
J 0
(2625 -1725);
DISPLAY 0.404255 (2625 -1725);
FORCEPROP 1 LAST LOCATION PR4007
J 0
(2400 -1700);
DISPLAY 0.638298 (2400 -1700);
FORCEPROP 1 LAST PATH I48
J 0
(2425 -1600);
DISPLAY 0.978723 (2425 -1600);
PAINT WHITE (2425 -1600);
DISPLAY INVISIBLE (2425 -1600);
FORCEPROP 2 LAST CDS_LIB pure_quanta
J 0
(2475 -1750);
DISPLAY INVISIBLE (2475 -1750);
FORCEPROP 0 LAST $SEC 1
J 0
(2375 -1675);
DISPLAY 0.680851 (2375 -1675);
PAINT MONO (2375 -1675);
DISPLAY INVISIBLE (2375 -1675);
FORCEPROP 0 LAST CDS_SEC 1
J 0
(2425 -1600);
DISPLAY INVISIBLE (2425 -1600);
FORCEPROP 1 LASTPIN (2375 -1750) $PN 1
J 0
(2387 -1738);
DISPLAY 0.787234 (2387 -1738);
PAINT MONO (2387 -1738);
DISPLAY INVISIBLE (2387 -1738);
FORCEPROP 1 LASTPIN (2575 -1750) $PN 2
J 0
(2537 -1738);
DISPLAY 0.787234 (2537 -1738);
PAINT MONO (2537 -1738);
DISPLAY INVISIBLE (2537 -1738);
FORCEADD VCCAUX15..1
(2850 -1675);
FORCEPROP 3 LASTPIN (2850 -1725) SIG_NAME P3V3_AUX\g
J 0
(2860 -1715);
DISPLAY 0.659574 (2860 -1715);
PAINT MONO (2860 -1715);
DISPLAY INVISIBLE (2860 -1715);
FORCEPROP 1 LAST HDL_POWER P3V3_AUX
J 1
(2850 -1650);
DISPLAY 0.574468 (2850 -1650);
PAINT GREEN (2850 -1650);
FORCEPROP 1 LAST PATH I49
J 0
(2900 -1650);
DISPLAY 0.872340 (2900 -1650);
PAINT AQUA (2900 -1650);
DISPLAY INVISIBLE (2900 -1650);
FORCEPROP 2 LAST CDS_LIB logical_power
J 0
(2850 -1675);
DISPLAY INVISIBLE (2850 -1675);
FORCEADD GND..1
(-675 -2125);
FORCEPROP 3 LASTPIN (-675 -2075) SIG_NAME GND\g
J 0
(-665 -2065);
DISPLAY 0.659574 (-665 -2065);
PAINT MONO (-665 -2065);
DISPLAY INVISIBLE (-665 -2065);
FORCEPROP 1 LAST PATH I5
J 0
(-600 -2125);
DISPLAY 0.872340 (-600 -2125);
PAINT AQUA (-600 -2125);
DISPLAY INVISIBLE (-600 -2125);
FORCEPROP 1 LAST SIZE 1B
J 0
(-600 -2175);
DISPLAY 0.872340 (-600 -2175);
PAINT GREEN (-600 -2175);
DISPLAY INVISIBLE (-600 -2175);
FORCEPROP 2 LAST CDS_LIB logical_power
J 0
(-675 -2125);
DISPLAY INVISIBLE (-675 -2125);
FORCEPROP 1 LAST HDL_POWER GND
J 0
(-675 -1975);
DISPLAY 0.872340 (-675 -1975);
PAINT GREEN (-675 -1975);
DISPLAY INVISIBLE (-675 -1975);
FORCEADD Q_RES..2
(3025 -1775);
FORCEPROP 1 LAST PART_NUMBER CS31002FB08
J 0
(3075 -1825);
DISPLAY 0.510638 (3075 -1825);
DISPLAY INVISIBLE (3075 -1825);
FORCEPROP 2 LAST ROOM SCM_P12V_BOM2
J 0
(3075 -1650);
DISPLAY 0.510638 (3075 -1650);
FORCEPROP 1 LAST VALUE 10K
J 0
(3075 -1725);
DISPLAY 0.510638 (3075 -1725);
FORCEPROP 1 LAST TOLERANCE 1%
J 0
(3075 -1750);
DISPLAY 0.510638 (3075 -1750);
FORCEPROP 1 LAST MATERIAL CHIP
J 0
(3075 -1800);
DISPLAY 0.510638 (3075 -1800);
FORCEPROP 1 LAST WATTAGE 1/16W
J 0
(3075 -1775);
DISPLAY 0.510638 (3075 -1775);
FORCEPROP 1 LAST PACK_TYPE 0402LF
J 0
(3075 -1850);
DISPLAY 0.510638 (3075 -1850);
FORCEPROP 1 LAST LOCATION PR4011
J 0
(3075 -1700);
DISPLAY 0.510638 (3075 -1700);
FORCEPROP 1 LAST PATH I50
J 0
(3075 -1600);
DISPLAY 0.978723 (3075 -1600);
PAINT WHITE (3075 -1600);
DISPLAY INVISIBLE (3075 -1600);
FORCEPROP 2 LAST CDS_LIB pure_quanta
J 0
(3025 -1775);
DISPLAY INVISIBLE (3025 -1775);
FORCEPROP 0 LAST $SEC 1
J 0
(3075 -1600);
DISPLAY INVISIBLE (3075 -1600);
FORCEPROP 0 LAST CDS_SEC 1
J 0
(3075 -1600);
DISPLAY INVISIBLE (3075 -1600);
FORCEPROP 1 LASTPIN (3025 -1675) $PN 1
J 0
(3030 -1713);
DISPLAY 0.787234 (3030 -1713);
PAINT MONO (3030 -1713);
DISPLAY INVISIBLE (3030 -1713);
FORCEPROP 1 LASTPIN (3025 -1875) $PN 2
J 0
(3030 -1865);
DISPLAY 0.787234 (3030 -1865);
PAINT MONO (3030 -1865);
DISPLAY INVISIBLE (3030 -1865);
FORCEADD Q_RES..2
(2625 -1275);
FORCEPROP 1 LAST PART_NUMBER CS37152FB05
J 0
(2675 -1325);
DISPLAY 0.510638 (2675 -1325);
DISPLAY INVISIBLE (2675 -1325);
FORCEPROP 1 LAST VALUE 71.5K
J 0
(2675 -1250);
DISPLAY 0.510638 (2675 -1250);
FORCEPROP 1 LAST PACK_TYPE 0402LF
J 0
(2675 -1350);
DISPLAY 0.510638 (2675 -1350);
FORCEPROP 1 LAST MATERIAL EMPTY
J 0
(2675 -1300);
DISPLAY 0.510638 (2675 -1300);
PAINT RED (2675 -1300);
FORCEPROP 1 LAST TOLERANCE 1%
J 0
(2675 -1275);
DISPLAY 0.510638 (2675 -1275);
FORCEPROP 1 LAST LOCATION PR4009
J 0
(2675 -1225);
DISPLAY 0.510638 (2675 -1225);
FORCEPROP 1 LASTPIN (2625 -1175) $PN 1
J 0
(2630 -1213);
DISPLAY 0.510638 (2630 -1213);
FORCEPROP 1 LASTPIN (2625 -1375) $PN 2
J 0
(2630 -1365);
DISPLAY 0.510638 (2630 -1365);
FORCEPROP 1 LAST PATH I51
J 0
(2675 -1100);
DISPLAY 0.978723 (2675 -1100);
PAINT WHITE (2675 -1100);
DISPLAY INVISIBLE (2675 -1100);
FORCEPROP 2 LAST CDS_LIB pure_quanta
J 0
(2625 -1275);
DISPLAY INVISIBLE (2625 -1275);
FORCEPROP 1 LAST WATTAGE 1/16W
J 0
(2650 -1300);
DISPLAY 0.723404 (2650 -1300);
PAINT SKYBLUE (2650 -1300);
DISPLAY INVISIBLE (2650 -1300);
FORCEPROP 0 LAST $SEC 1
J 0
(2650 -1150);
DISPLAY 0.680851 (2650 -1150);
PAINT MONO (2650 -1150);
DISPLAY INVISIBLE (2650 -1150);
FORCEPROP 0 LAST CDS_SEC 1
J 0
(2650 -1150);
DISPLAY 1.021277 (2650 -1150);
DISPLAY INVISIBLE (2650 -1150);
FORCEADD Q_RES..2
(3025 -1350);
FORCEPROP 1 LAST PART_NUMBER CS41202FB05
J 0
(3075 -1425);
DISPLAY 0.510638 (3075 -1425);
DISPLAY INVISIBLE (3075 -1425);
FORCEPROP 1 LAST WATTAGE 1/16W
J 0
(3075 -1375);
DISPLAY 0.510638 (3075 -1375);
FORCEPROP 1 LAST MATERIAL CHIP
J 0
(3075 -1400);
DISPLAY 0.510638 (3075 -1400);
FORCEPROP 1 LAST VALUE 120K
J 0
(3075 -1325);
DISPLAY 0.510638 (3075 -1325);
FORCEPROP 1 LAST PACK_TYPE 0402LF
J 0
(3075 -1450);
DISPLAY 0.510638 (3075 -1450);
FORCEPROP 1 LAST TOLERANCE 1%
J 0
(3075 -1350);
DISPLAY 0.510638 (3075 -1350);
FORCEPROP 2 LAST ROOM SCM_P12V_BOM2
J 0
(3075 -1275);
DISPLAY 0.510638 (3075 -1275);
FORCEPROP 1 LAST LOCATION PR4010
J 0
(3075 -1300);
DISPLAY 0.510638 (3075 -1300);
FORCEPROP 1 LAST PATH I52
J 0
(3075 -1175);
DISPLAY 0.978723 (3075 -1175);
PAINT WHITE (3075 -1175);
DISPLAY INVISIBLE (3075 -1175);
FORCEPROP 2 LAST CDS_LIB pure_quanta
J 0
(3025 -1350);
DISPLAY INVISIBLE (3025 -1350);
FORCEPROP 0 LAST $SEC 1
J 0
(3075 -1175);
DISPLAY INVISIBLE (3075 -1175);
FORCEPROP 0 LAST CDS_SEC 1
J 0
(3075 -1175);
DISPLAY INVISIBLE (3075 -1175);
FORCEPROP 1 LASTPIN (3025 -1250) $PN 1
J 0
(3030 -1288);
DISPLAY 0.787234 (3030 -1288);
PAINT MONO (3030 -1288);
DISPLAY INVISIBLE (3030 -1288);
FORCEPROP 1 LASTPIN (3025 -1450) $PN 2
J 0
(3030 -1440);
DISPLAY 0.787234 (3030 -1440);
PAINT MONO (3030 -1440);
DISPLAY INVISIBLE (3030 -1440);
FORCEADD Q_CAP..1
(3550 -1775);
FORCEPROP 1 LAST PART_NUMBER CH5223M1900
J 0
(3625 -1850);
DISPLAY 0.510638 (3625 -1850);
DISPLAY INVISIBLE (3625 -1850);
FORCEPROP 2 LAST ROOM SCM_P12V_BOM2
J 0
(3625 -1675);
DISPLAY 0.510638 (3625 -1675);
FORCEPROP 1 LAST VOLTAGE 16V
J 0
(3625 -1775);
DISPLAY 0.510638 (3625 -1775);
FORCEPROP 1 LAST VALUE 2.2UF
J 0
(3625 -1750);
DISPLAY 0.510638 (3625 -1750);
FORCEPROP 1 LAST TOLERANCE 20%
J 0
(3625 -1800);
DISPLAY 0.510638 (3625 -1800);
FORCEPROP 1 LAST MATERIAL X7R
J 0
(3625 -1825);
DISPLAY 0.510638 (3625 -1825);
FORCEPROP 1 LAST PACK_TYPE C0603
J 0
(3625 -1875);
DISPLAY 0.510638 (3625 -1875);
FORCEPROP 1 LAST LOCATION PC2239
J 0
(3625 -1725);
DISPLAY 0.510638 (3625 -1725);
FORCEPROP 1 LAST PATH I53
J 0
(3600 -1625);
DISPLAY 0.978723 (3600 -1625);
PAINT WHITE (3600 -1625);
DISPLAY INVISIBLE (3600 -1625);
FORCEPROP 2 LAST CDS_LIB pure_quanta
J 0
(3550 -1775);
DISPLAY INVISIBLE (3550 -1775);
FORCEPROP 0 LAST $SEC 1
J 0
(3625 -1625);
DISPLAY INVISIBLE (3625 -1625);
FORCEPROP 0 LAST CDS_SEC 1
J 0
(3625 -1625);
DISPLAY INVISIBLE (3625 -1625);
FORCEPROP 1 LASTPIN (3550 -1675) $PN 1
J 0
(3560 -1695);
DISPLAY 0.787234 (3560 -1695);
PAINT MONO (3560 -1695);
DISPLAY INVISIBLE (3560 -1695);
FORCEPROP 1 LASTPIN (3550 -1875) $PN 2
J 0
(3560 -1895);
DISPLAY 0.787234 (3560 -1895);
PAINT MONO (3560 -1895);
DISPLAY INVISIBLE (3560 -1895);
FORCEADD Q_RES..2
(3550 -1350);
FORCEPROP 1 LAST PART_NUMBER CS04993F909
J 0
(3625 -1425);
DISPLAY 0.510638 (3625 -1425);
DISPLAY INVISIBLE (3625 -1425);
FORCEPROP 1 LAST PACK_TYPE 0603LF
J 0
(3625 -1450);
DISPLAY 0.510638 (3625 -1450);
FORCEPROP 1 LAST TOLERANCE 1%
J 0
(3625 -1350);
DISPLAY 0.510638 (3625 -1350);
FORCEPROP 1 LAST WATTAGE 1/10W
J 0
(3625 -1375);
DISPLAY 0.510638 (3625 -1375);
FORCEPROP 1 LAST MATERIAL CHIP
J 0
(3625 -1400);
DISPLAY 0.510638 (3625 -1400);
FORCEPROP 1 LAST VALUE 49.9
J 0
(3625 -1325);
DISPLAY 0.510638 (3625 -1325);
FORCEPROP 2 LAST ROOM SCM_P12V_BOM2
J 0
(3625 -1275);
DISPLAY 0.510638 (3625 -1275);
FORCEPROP 1 LAST LOCATION PR4014
J 0
(3625 -1300);
DISPLAY 0.510638 (3625 -1300);
FORCEPROP 1 LASTPIN (3550 -1250) $PN 1
J 0
(3555 -1288);
DISPLAY 0.510638 (3555 -1288);
PAINT MONO (3555 -1288);
FORCEPROP 1 LASTPIN (3550 -1450) $PN 2
J 0
(3555 -1440);
DISPLAY 0.510638 (3555 -1440);
PAINT MONO (3555 -1440);
FORCEPROP 1 LAST PATH I54
J 0
(3600 -1175);
DISPLAY 0.978723 (3600 -1175);
PAINT WHITE (3600 -1175);
DISPLAY INVISIBLE (3600 -1175);
FORCEPROP 2 LAST CDS_LIB pure_quanta
J 0
(3550 -1350);
DISPLAY INVISIBLE (3550 -1350);
FORCEPROP 0 LAST $SEC 1
J 0
(3600 -1175);
DISPLAY 0.680851 (3600 -1175);
PAINT MONO (3600 -1175);
DISPLAY INVISIBLE (3600 -1175);
FORCEPROP 0 LAST CDS_SEC 1
J 0
(3600 -1175);
DISPLAY 1.021277 (3600 -1175);
DISPLAY INVISIBLE (3600 -1175);
FORCEADD UNIVERSAL_POWER..1
(3550 -1050);
FORCEPROP 3 LASTPIN (3550 -1100) SIG_NAME P12V_AUX\g
J 0
(3560 -1090);
DISPLAY 0.659574 (3560 -1090);
PAINT MONO (3560 -1090);
DISPLAY INVISIBLE (3560 -1090);
FORCEPROP 1 LAST HDL_POWER P12V_AUX
J 1
(3550 -1000);
DISPLAY 0.510638 (3550 -1000);
PAINT GREEN (3550 -1000);
FORCEPROP 1 LAST PATH I55
J 0
(3600 -1025);
DISPLAY 0.872340 (3600 -1025);
PAINT AQUA (3600 -1025);
DISPLAY INVISIBLE (3600 -1025);
FORCEPROP 2 LAST CDS_LIB logical_power
J 0
(3550 -1050);
DISPLAY INVISIBLE (3550 -1050);
FORCEADD GND..1
(3900 -1200);
FORCEPROP 3 LASTPIN (3900 -1150) SIG_NAME GND\g
J 0
(3910 -1140);
DISPLAY 0.659574 (3910 -1140);
PAINT MONO (3910 -1140);
DISPLAY INVISIBLE (3910 -1140);
FORCEPROP 1 LAST PATH I56
J 0
(3975 -1200);
DISPLAY 0.872340 (3975 -1200);
PAINT AQUA (3975 -1200);
DISPLAY INVISIBLE (3975 -1200);
FORCEPROP 1 LAST SIZE 1B
J 0
(3975 -1250);
DISPLAY 0.872340 (3975 -1250);
PAINT GREEN (3975 -1250);
DISPLAY INVISIBLE (3975 -1250);
FORCEPROP 2 LAST CDS_LIB logical_power
J 0
(3900 -1200);
DISPLAY INVISIBLE (3900 -1200);
FORCEPROP 1 LAST HDL_POWER GND
J 0
(3900 -1050);
DISPLAY 0.872340 (3900 -1050);
PAINT GREEN (3900 -1050);
DISPLAY INVISIBLE (3900 -1050);
FORCEADD Q_CAP..1
R 2
(3900 -925);
FORCEPROP 1 LAST PART_NUMBER CH4104K1B00
J 0
(3975 -1000);
DISPLAY 0.510638 (3975 -1000);
DISPLAY INVISIBLE (3975 -1000);
FORCEPROP 1 LAST MATERIAL X7R
J 0
(3975 -975);
DISPLAY 0.510638 (3975 -975);
FORCEPROP 2 LAST ROOM SCM_P12V_BOM2
J 0
(3975 -825);
DISPLAY 0.510638 (3975 -825);
FORCEPROP 1 LAST VOLTAGE 25V
J 0
(3975 -925);
DISPLAY 0.510638 (3975 -925);
FORCEPROP 1 LAST VALUE 0.1UF
J 0
(3975 -900);
DISPLAY 0.510638 (3975 -900);
FORCEPROP 1 LAST TOLERANCE 10%
J 0
(3975 -950);
DISPLAY 0.510638 (3975 -950);
FORCEPROP 1 LAST PACK_TYPE 0402
J 0
(3975 -1025);
DISPLAY 0.510638 (3975 -1025);
FORCEPROP 1 LAST LOCATION PC2241
J 0
(3975 -875);
DISPLAY 0.510638 (3975 -875);
FORCEPROP 1 LASTPIN (3900 -825) $PN 1
J 2
(3890 -845);
DISPLAY 0.510638 (3890 -845);
PAINT MONO (3890 -845);
FORCEPROP 1 LASTPIN (3900 -1025) $PN 2
J 2
(3890 -1045);
DISPLAY 0.510638 (3890 -1045);
PAINT MONO (3890 -1045);
FORCEPROP 1 LAST PATH I57
J 2
(3850 -775);
DISPLAY 0.978723 (3850 -775);
PAINT WHITE (3850 -775);
DISPLAY INVISIBLE (3850 -775);
FORCEPROP 2 LAST CDS_LIB pure_quanta
J 0
(3900 -925);
DISPLAY INVISIBLE (3900 -925);
FORCEPROP 0 LAST $SEC 1
J 0
(4250 -775);
DISPLAY 0.680851 (4250 -775);
PAINT MONO (4250 -775);
DISPLAY INVISIBLE (4250 -775);
FORCEPROP 0 LAST CDS_SEC 1
J 0
(4250 -775);
DISPLAY 1.021277 (4250 -775);
DISPLAY INVISIBLE (4250 -775);
FORCEADD UNIVERSAL_POWER..1
R 2
(3900 -650);
FORCEPROP 3 LASTPIN (3900 -700) SIG_NAME P12V_SCM_R\g
J 0
(3910 -690);
DISPLAY 0.659574 (3910 -690);
PAINT MONO (3910 -690);
DISPLAY INVISIBLE (3910 -690);
FORCEPROP 1 LAST HDL_POWER P12V_SCM_R
J 1
(3900 -600);
DISPLAY 0.510638 (3900 -600);
PAINT GREEN (3900 -600);
FORCEPROP 1 LAST PATH I58
J 2
(3850 -625);
DISPLAY 0.872340 (3850 -625);
PAINT AQUA (3850 -625);
DISPLAY INVISIBLE (3850 -625);
FORCEPROP 2 LAST CDS_LIB logical_power
J 0
(3900 -650);
DISPLAY INVISIBLE (3900 -650);
FORCEADD OFFPAGE..2
(4200 -1625);
PAINT AQUA (4200 -1625);
FORCEPROP 2 LAST $XR0 242 
J 0
(4389 -1625);
DISPLAY 0.638298 (4389 -1625);
PAINT MONO (4389 -1625);
FORCEPROP 2 LAST PATH I59
J 0
(4400 -1575);
DISPLAY 1.021277 (4400 -1575);
DISPLAY INVISIBLE (4400 -1575);
FORCEPROP 2 LAST CDS_LIB standard
J 0
(4200 -1625);
DISPLAY INVISIBLE (4200 -1625);
FORCEPROP 1 LAST OFFPAGE TRUE
J 0
(4525 -1750);
DISPLAY 0.872340 (4525 -1750);
PAINT AQUA (4525 -1750);
DISPLAY INVISIBLE (4525 -1750);
FORCEPROP 1 LAST COMMENT_BODY TRUE
J 0
(4155 -1720);
DISPLAY 0.872340 (4155 -1720);
PAINT GREEN (4155 -1720);
DISPLAY INVISIBLE (4155 -1720);
FORCEADD GND..1
(-250 -2375);
FORCEPROP 3 LASTPIN (-250 -2325) SIG_NAME GND\g
J 0
(-240 -2315);
DISPLAY 0.659574 (-240 -2315);
PAINT MONO (-240 -2315);
DISPLAY INVISIBLE (-240 -2315);
FORCEPROP 1 LAST PATH I6
J 0
(-175 -2375);
DISPLAY 0.872340 (-175 -2375);
PAINT AQUA (-175 -2375);
DISPLAY INVISIBLE (-175 -2375);
FORCEPROP 1 LAST SIZE 1B
J 0
(-175 -2425);
DISPLAY 0.872340 (-175 -2425);
PAINT GREEN (-175 -2425);
DISPLAY INVISIBLE (-175 -2425);
FORCEPROP 2 LAST CDS_LIB logical_power
J 0
(-250 -2375);
DISPLAY INVISIBLE (-250 -2375);
FORCEPROP 1 LAST HDL_POWER GND
J 0
(-250 -2225);
DISPLAY 0.872340 (-250 -2225);
PAINT GREEN (-250 -2225);
DISPLAY INVISIBLE (-250 -2225);
FORCEADD GND..1
(75 750);
FORCEPROP 3 LASTPIN (75 800) SIG_NAME GND\g
J 0
(85 810);
DISPLAY 0.659574 (85 810);
PAINT MONO (85 810);
DISPLAY INVISIBLE (85 810);
FORCEPROP 1 LAST PATH I60
J 0
(150 750);
DISPLAY 0.872340 (150 750);
PAINT AQUA (150 750);
DISPLAY INVISIBLE (150 750);
FORCEPROP 2 LAST CDS_LIB logical_power
J 0
(75 750);
DISPLAY INVISIBLE (75 750);
FORCEPROP 1 LAST SIZE 1B
J 0
(150 700);
DISPLAY 0.872340 (150 700);
PAINT GREEN (150 700);
DISPLAY INVISIBLE (150 700);
FORCEPROP 1 LAST HDL_POWER GND
J 0
(75 900);
DISPLAY 0.872340 (75 900);
PAINT GREEN (75 900);
DISPLAY INVISIBLE (75 900);
FORCEADD Q_RES..2
(75 975);
FORCEPROP 1 LAST PART_NUMBER CS31502FB05
J 0
(125 925);
DISPLAY 0.510638 (125 925);
DISPLAY INVISIBLE (125 925);
FORCEPROP 2 LAST ROOM SCM_P12V_BOM1
J 0
(125 1100);
DISPLAY 0.510638 (125 1100);
FORCEPROP 1 LAST TOLERANCE 1%
J 0
(125 1000);
DISPLAY 0.510638 (125 1000);
FORCEPROP 1 LAST WATTAGE 1/16W
J 0
(125 975);
DISPLAY 0.510638 (125 975);
FORCEPROP 1 LAST MATERIAL EMPTY
J 0
(125 950);
DISPLAY 0.510638 (125 950);
PAINT RED (125 950);
FORCEPROP 1 LAST VALUE 15K
J 0
(125 1025);
DISPLAY 0.510638 (125 1025);
FORCEPROP 1 LAST PACK_TYPE 0402LF
J 0
(125 900);
DISPLAY 0.510638 (125 900);
FORCEPROP 1 LAST LOCATION PR4002
J 0
(125 1050);
DISPLAY 0.510638 (125 1050);
FORCEPROP 1 LASTPIN (75 1075) $PN 1
J 0
(80 1037);
DISPLAY 0.510638 (80 1037);
PAINT MONO (80 1037);
FORCEPROP 1 LASTPIN (75 875) $PN 2
J 0
(80 885);
DISPLAY 0.510638 (80 885);
PAINT MONO (80 885);
FORCEPROP 1 LAST PATH I61
J 0
(125 1150);
DISPLAY 0.978723 (125 1150);
PAINT WHITE (125 1150);
DISPLAY INVISIBLE (125 1150);
FORCEPROP 2 LAST CDS_LIB pure_quanta
J 0
(75 975);
DISPLAY INVISIBLE (75 975);
FORCEPROP 0 LAST $SEC 1
J 0
(125 1100);
DISPLAY 0.680851 (125 1100);
PAINT MONO (125 1100);
DISPLAY INVISIBLE (125 1100);
FORCEPROP 0 LAST CDS_SEC 1
J 0
(125 1100);
DISPLAY 1.021277 (125 1100);
DISPLAY INVISIBLE (125 1100);
FORCEADD GND..1
(925 750);
FORCEPROP 3 LASTPIN (925 800) SIG_NAME GND\g
J 0
(935 810);
DISPLAY 0.659574 (935 810);
PAINT MONO (935 810);
DISPLAY INVISIBLE (935 810);
FORCEPROP 1 LAST PATH I62
J 0
(1000 750);
DISPLAY 0.872340 (1000 750);
PAINT AQUA (1000 750);
DISPLAY INVISIBLE (1000 750);
FORCEPROP 1 LAST SIZE 1B
J 0
(1000 700);
DISPLAY 0.872340 (1000 700);
PAINT GREEN (1000 700);
DISPLAY INVISIBLE (1000 700);
FORCEPROP 2 LAST CDS_LIB logical_power
J 0
(925 750);
DISPLAY INVISIBLE (925 750);
FORCEPROP 1 LAST HDL_POWER GND
J 0
(925 900);
DISPLAY 0.872340 (925 900);
PAINT GREEN (925 900);
DISPLAY INVISIBLE (925 900);
FORCEADD Q_RES..2
(925 975);
FORCEPROP 1 LAST PART_NUMBER CS31782FB04
J 0
(975 900);
DISPLAY 0.510638 (975 900);
DISPLAY INVISIBLE (975 900);
FORCEPROP 1 LAST PACK_TYPE 0402LF
J 0
(975 875);
DISPLAY 0.510638 (975 875);
FORCEPROP 1 LAST WATTAGE 1/16W
J 0
(975 950);
DISPLAY 0.510638 (975 950);
FORCEPROP 1 LAST MATERIAL EMPTY
J 0
(975 925);
DISPLAY 0.510638 (975 925);
PAINT RED (975 925);
FORCEPROP 1 LAST TOLERANCE 1%
J 0
(975 975);
DISPLAY 0.510638 (975 975);
FORCEPROP 1 LAST VALUE 17.8K
J 0
(975 1000);
DISPLAY 0.510638 (975 1000);
FORCEPROP 2 LAST ROOM SCM_P12V_BOM1
J 0
(975 1075);
DISPLAY 0.510638 (975 1075);
FORCEPROP 1 LAST LOCATION PR4004
J 0
(975 1025);
DISPLAY 0.510638 (975 1025);
FORCEPROP 1 LASTPIN (925 1075) $PN 1
J 0
(930 1037);
DISPLAY 0.510638 (930 1037);
PAINT MONO (930 1037);
FORCEPROP 1 LASTPIN (925 875) $PN 2
J 0
(930 885);
DISPLAY 0.510638 (930 885);
PAINT MONO (930 885);
FORCEPROP 1 LAST PATH I63
J 0
(975 1150);
DISPLAY 0.978723 (975 1150);
PAINT WHITE (975 1150);
DISPLAY INVISIBLE (975 1150);
FORCEPROP 2 LAST CDS_LIB pure_quanta
J 0
(925 975);
DISPLAY INVISIBLE (925 975);
FORCEPROP 0 LAST $SEC 1
J 0
(975 1125);
DISPLAY 0.680851 (975 1125);
PAINT MONO (975 1125);
DISPLAY INVISIBLE (975 1125);
FORCEPROP 0 LAST CDS_SEC 1
J 0
(975 1100);
DISPLAY INVISIBLE (975 1100);
FORCEADD Q_RES..2
(75 1250);
FORCEPROP 1 LAST PART_NUMBER CS26802FB02
J 0
(125 1200);
DISPLAY 0.510638 (125 1200);
DISPLAY INVISIBLE (125 1200);
FORCEPROP 1 LAST MATERIAL EMPTY
J 0
(125 1225);
DISPLAY 0.510638 (125 1225);
PAINT RED (125 1225);
FORCEPROP 1 LAST PACK_TYPE 0402LF
J 0
(125 1175);
DISPLAY 0.510638 (125 1175);
FORCEPROP 2 LAST ROOM SCM_P12V_BOM1
J 0
(125 1375);
DISPLAY 0.510638 (125 1375);
FORCEPROP 1 LAST VALUE 6.8K
J 0
(125 1300);
DISPLAY 0.510638 (125 1300);
FORCEPROP 1 LAST TOLERANCE 1%
J 0
(125 1275);
DISPLAY 0.510638 (125 1275);
FORCEPROP 1 LAST WATTAGE 1/16W
J 0
(125 1250);
DISPLAY 0.510638 (125 1250);
FORCEPROP 1 LAST LOCATION PR4001
J 0
(125 1325);
DISPLAY 0.510638 (125 1325);
FORCEPROP 1 LASTPIN (75 1350) $PN 1
J 0
(80 1312);
DISPLAY 0.510638 (80 1312);
PAINT MONO (80 1312);
FORCEPROP 1 LASTPIN (75 1150) $PN 2
J 0
(80 1160);
DISPLAY 0.510638 (80 1160);
PAINT MONO (80 1160);
FORCEPROP 1 LAST PATH I64
J 0
(125 1425);
DISPLAY 0.978723 (125 1425);
PAINT WHITE (125 1425);
DISPLAY INVISIBLE (125 1425);
FORCEPROP 2 LAST CDS_LIB pure_quanta
J 0
(75 1250);
DISPLAY INVISIBLE (75 1250);
FORCEPROP 0 LAST $SEC 1
J 0
(125 1375);
DISPLAY 0.680851 (125 1375);
PAINT MONO (125 1375);
DISPLAY INVISIBLE (125 1375);
FORCEPROP 0 LAST CDS_SEC 1
J 0
(125 1375);
DISPLAY 1.021277 (125 1375);
DISPLAY INVISIBLE (125 1375);
FORCEADD GND..1
(400 1425);
FORCEPROP 3 LASTPIN (400 1475) SIG_NAME GND\g
J 0
(410 1485);
DISPLAY 0.659574 (410 1485);
PAINT MONO (410 1485);
DISPLAY INVISIBLE (410 1485);
FORCEPROP 1 LAST PATH I65
J 0
(475 1425);
DISPLAY 0.872340 (475 1425);
PAINT AQUA (475 1425);
DISPLAY INVISIBLE (475 1425);
FORCEPROP 1 LAST SIZE 1B
J 0
(475 1375);
DISPLAY 0.872340 (475 1375);
PAINT GREEN (475 1375);
DISPLAY INVISIBLE (475 1375);
FORCEPROP 2 LAST CDS_LIB logical_power
J 0
(400 1425);
DISPLAY INVISIBLE (400 1425);
FORCEPROP 1 LAST HDL_POWER GND
J 0
(400 1575);
DISPLAY 0.872340 (400 1575);
PAINT GREEN (400 1575);
DISPLAY INVISIBLE (400 1575);
FORCEADD Q_CAP..1
R 1
(625 1500);
FORCEPROP 1 LAST PART_NUMBER CH5104KEB02
J 0
(675 1450);
DISPLAY 0.510638 (675 1450);
DISPLAY INVISIBLE (675 1450);
FORCEPROP 1 LAST PACK_TYPE C0402
J 0
(450 1450);
DISPLAY 0.510638 (450 1450);
FORCEPROP 1 LAST VOLTAGE 25V
J 0
(775 1550);
DISPLAY 0.510638 (775 1550);
FORCEPROP 1 LAST VALUE 1UF
J 0
(600 1550);
DISPLAY 0.510638 (600 1550);
FORCEPROP 2 LAST ROOM SCM_P12V_BOM1
J 0
(450 1600);
DISPLAY 0.510638 (450 1600);
FORCEPROP 1 LAST LOCATION PC2234
J 0
(450 1550);
DISPLAY 0.510638 (450 1550);
FORCEPROP 1 LASTPIN (525 1500) $PN 1
R 1
J 0
(545 1510);
DISPLAY 0.510638 (545 1510);
PAINT MONO (545 1510);
FORCEPROP 1 LASTPIN (725 1500) $PN 2
R 1
J 0
(745 1510);
DISPLAY 0.510638 (745 1510);
PAINT MONO (745 1510);
FORCEPROP 1 LAST PATH I66
R 1
J 0
(475 1550);
DISPLAY 0.978723 (475 1550);
PAINT WHITE (475 1550);
DISPLAY INVISIBLE (475 1550);
FORCEPROP 1 LAST MATERIAL EMPTY
R 1
J 0
(625 1550);
DISPLAY 0.638298 (625 1550);
DISPLAY INVISIBLE (625 1550);
FORCEPROP 1 LAST TOLERANCE 10%
R 1
J 0
(675 1550);
DISPLAY 0.638298 (675 1550);
DISPLAY INVISIBLE (675 1550);
FORCEPROP 2 LAST CDS_LIB pure_quanta
J 0
(625 1500);
DISPLAY INVISIBLE (625 1500);
FORCEPROP 0 LAST $SEC 1
R 1
J 0
(450 1600);
DISPLAY 0.680851 (450 1600);
PAINT MONO (450 1600);
DISPLAY INVISIBLE (450 1600);
FORCEPROP 0 LAST CDS_SEC 1
R 1
J 0
(450 1600);
DISPLAY 1.021277 (450 1600);
DISPLAY INVISIBLE (450 1600);
FORCEADD Q_RES..2
(75 1925);
FORCEPROP 1 LAST PART_NUMBER CS41602FB05
J 0
(125 1875);
DISPLAY 0.510638 (125 1875);
DISPLAY INVISIBLE (125 1875);
FORCEPROP 1 LAST TOLERANCE 1%
J 0
(125 1950);
DISPLAY 0.510638 (125 1950);
FORCEPROP 1 LAST PACK_TYPE 0402LF
J 0
(125 1850);
DISPLAY 0.510638 (125 1850);
FORCEPROP 2 LAST ROOM SCM_P12V_BOM1
J 0
(125 2050);
DISPLAY 0.510638 (125 2050);
FORCEPROP 1 LAST VALUE 160K
J 0
(125 1975);
DISPLAY 0.510638 (125 1975);
FORCEPROP 1 LAST WATTAGE 1/16W
J 0
(125 1925);
DISPLAY 0.510638 (125 1925);
FORCEPROP 1 LAST MATERIAL EMPTY
J 0
(125 1900);
DISPLAY 0.510638 (125 1900);
PAINT RED (125 1900);
FORCEPROP 1 LAST LOCATION PR4000
J 0
(125 2000);
DISPLAY 0.510638 (125 2000);
FORCEPROP 1 LASTPIN (75 2025) $PN 1
J 0
(80 1987);
DISPLAY 0.510638 (80 1987);
PAINT MONO (80 1987);
FORCEPROP 1 LASTPIN (75 1825) $PN 2
J 0
(80 1835);
DISPLAY 0.510638 (80 1835);
PAINT MONO (80 1835);
FORCEPROP 1 LAST PATH I67
J 0
(125 2100);
DISPLAY 0.978723 (125 2100);
PAINT WHITE (125 2100);
DISPLAY INVISIBLE (125 2100);
FORCEPROP 2 LAST CDS_LIB pure_quanta
J 0
(75 1925);
DISPLAY INVISIBLE (75 1925);
FORCEPROP 0 LAST $SEC 1
J 0
(125 2050);
DISPLAY 0.680851 (125 2050);
PAINT MONO (125 2050);
DISPLAY INVISIBLE (125 2050);
FORCEPROP 0 LAST CDS_SEC 1
J 0
(125 2050);
DISPLAY 1.021277 (125 2050);
DISPLAY INVISIBLE (125 2050);
FORCEADD Q_CAP..1
(400 1800);
FORCEPROP 1 LAST PART_NUMBER CH5104KEB02
J 0
(450 1700);
DISPLAY 0.510638 (450 1700);
DISPLAY INVISIBLE (450 1700);
FORCEPROP 1 LAST VOLTAGE 25V
J 0
(450 1750);
DISPLAY 0.510638 (450 1750);
FORCEPROP 1 LAST PACK_TYPE C0402
J 0
(450 1725);
DISPLAY 0.510638 (450 1725);
FORCEPROP 1 LAST VALUE 1UF
J 0
(450 1800);
DISPLAY 0.510638 (450 1800);
FORCEPROP 1 LAST MATERIAL EMPTY
J 0
(450 1775);
DISPLAY 0.510638 (450 1775);
PAINT RED (450 1775);
FORCEPROP 2 LAST ROOM SCM_P12V_BOM1
J 0
(450 1875);
DISPLAY 0.510638 (450 1875);
FORCEPROP 1 LAST LOCATION PC2233
J 0
(450 1825);
DISPLAY 0.510638 (450 1825);
FORCEPROP 1 LASTPIN (400 1900) $PN 1
J 0
(410 1880);
DISPLAY 0.510638 (410 1880);
PAINT MONO (410 1880);
FORCEPROP 1 LASTPIN (400 1700) $PN 2
J 0
(410 1680);
DISPLAY 0.510638 (410 1680);
PAINT MONO (410 1680);
FORCEPROP 1 LAST PATH I68
J 0
(450 1950);
DISPLAY 0.978723 (450 1950);
PAINT WHITE (450 1950);
DISPLAY INVISIBLE (450 1950);
FORCEPROP 1 LAST TOLERANCE 10%
J 0
(450 1750);
DISPLAY 0.638298 (450 1750);
DISPLAY INVISIBLE (450 1750);
FORCEPROP 2 LAST CDS_LIB pure_quanta
J 0
(400 1800);
DISPLAY INVISIBLE (400 1800);
FORCEPROP 0 LAST $SEC 1
J 0
(450 1875);
DISPLAY 0.680851 (450 1875);
PAINT MONO (450 1875);
DISPLAY INVISIBLE (450 1875);
FORCEPROP 0 LAST CDS_SEC 1
J 0
(450 1875);
DISPLAY 1.021277 (450 1875);
DISPLAY INVISIBLE (450 1875);
FORCEADD MAX15090BEWIT..1
(1675 1500);
FORCEPROP 1 LAST PART_NUMBER AL015080B00
J 0
(1422 2144);
DISPLAY 0.510638 (1422 2144);
PAINT GREEN (1422 2144);
DISPLAY INVISIBLE (1422 2144);
FORCEPROP 2 LAST PART_TYPE SMLF
J 0
(1425 2325);
DISPLAY 0.510638 (1425 2325);
FORCEPROP 1 LAST MATERIAL EMPTY
J 0
(1422 2055);
DISPLAY 0.510638 (1422 2055);
PAINT RED (1422 2055);
FORCEPROP 2 LAST VALUE MAX15090BEWI+T
J 0
(1425 2275);
DISPLAY 0.510638 (1425 2275);
FORCEPROP 2 LAST ROOM SCM_P12V_BOM1
J 0
(1425 2375);
DISPLAY 0.510638 (1425 2375);
FORCEPROP 1 LAST LOCATION PU300
J 0
(1422 2228);
DISPLAY 0.510638 (1422 2228);
PAINT GREEN (1422 2228);
FORCEPROP 0 LASTPIN (1275 1200) $PN B1
J 2
(1265 1210);
DISPLAY 0.510638 (1265 1210);
PAINT MONO (1265 1210);
FORCEPROP 0 LASTPIN (2075 1200) $PN A7
J 0
(2085 1210);
DISPLAY 0.510638 (2085 1210);
PAINT MONO (2085 1210);
FORCEPROP 0 LASTPIN (1275 1100) $PN B7
J 2
(1265 1110);
DISPLAY 0.510638 (1265 1110);
PAINT MONO (1265 1110);
FORCEPROP 0 LASTPIN (2075 1400) $PN C7
J 0
(2085 1410);
DISPLAY 0.510638 (2085 1410);
PAINT MONO (2085 1410);
FORCEPROP 0 LASTPIN (2075 1600) $PN A6
J 0
(2085 1610);
DISPLAY 0.510638 (2085 1610);
PAINT MONO (2085 1610);
FORCEPROP 0 LASTPIN (2075 1100) $PN B2
J 0
(2085 1110);
DISPLAY 0.510638 (2085 1110);
PAINT MONO (2085 1110);
FORCEPROP 0 LASTPIN (2075 1050) $PN C1
J 0
(2085 1060);
DISPLAY 0.510638 (2085 1060);
PAINT MONO (2085 1060);
FORCEPROP 0 LASTPIN (2075 1000) $PN C2
J 0
(2085 1010);
DISPLAY 0.510638 (2085 1010);
PAINT MONO (2085 1010);
FORCEPROP 0 LASTPIN (1275 2000) $PN A3
J 2
(1265 2010);
DISPLAY 0.510638 (1265 2010);
PAINT MONO (1265 2010);
FORCEPROP 0 LASTPIN (1275 1950) $PN A5
J 2
(1265 1960);
DISPLAY 0.510638 (1265 1960);
PAINT MONO (1265 1960);
FORCEPROP 0 LASTPIN (1275 1900) $PN B3
J 2
(1265 1910);
DISPLAY 0.510638 (1265 1910);
PAINT MONO (1265 1910);
FORCEPROP 0 LASTPIN (1275 1850) $PN B5
J 2
(1265 1860);
DISPLAY 0.510638 (1265 1860);
PAINT MONO (1265 1860);
FORCEPROP 0 LASTPIN (1275 1800) $PN C3
J 2
(1265 1810);
DISPLAY 0.510638 (1265 1810);
PAINT MONO (1265 1810);
FORCEPROP 0 LASTPIN (1275 1750) $PN C5
J 2
(1265 1760);
DISPLAY 0.510638 (1265 1760);
PAINT MONO (1265 1760);
FORCEPROP 0 LASTPIN (1275 1700) $PN D5
J 2
(1265 1710);
DISPLAY 0.510638 (1265 1710);
PAINT MONO (1265 1710);
FORCEPROP 0 LASTPIN (2075 1300) $PN A1
J 0
(2085 1310);
DISPLAY 0.510638 (2085 1310);
PAINT MONO (2085 1310);
FORCEPROP 0 LASTPIN (2075 2000) $PN A4
J 0
(2085 2010);
DISPLAY 0.510638 (2085 2010);
PAINT MONO (2085 2010);
FORCEPROP 0 LASTPIN (2075 1950) $PN B4
J 0
(2085 1960);
DISPLAY 0.510638 (2085 1960);
PAINT MONO (2085 1960);
FORCEPROP 0 LASTPIN (2075 1900) $PN B6
J 0
(2085 1910);
DISPLAY 0.510638 (2085 1910);
PAINT MONO (2085 1910);
FORCEPROP 0 LASTPIN (2075 1850) $PN C4
J 0
(2085 1860);
DISPLAY 0.510638 (2085 1860);
PAINT MONO (2085 1860);
FORCEPROP 0 LASTPIN (2075 1800) $PN C6
J 0
(2085 1810);
DISPLAY 0.510638 (2085 1810);
PAINT MONO (2085 1810);
FORCEPROP 0 LASTPIN (2075 1750) $PN D4
J 0
(2085 1760);
DISPLAY 0.510638 (2085 1760);
PAINT MONO (2085 1760);
FORCEPROP 0 LASTPIN (2075 1700) $PN D6
J 0
(2085 1710);
DISPLAY 0.510638 (2085 1710);
PAINT MONO (2085 1710);
FORCEPROP 0 LASTPIN (1275 1300) $PN D3
J 2
(1265 1310);
DISPLAY 0.510638 (1265 1310);
PAINT MONO (1265 1310);
FORCEPROP 0 LASTPIN (2075 1500) $PN D7
J 0
(2085 1510);
DISPLAY 0.510638 (2085 1510);
PAINT MONO (2085 1510);
FORCEPROP 0 LASTPIN (1275 1500) $PN D1
J 2
(1265 1510);
DISPLAY 0.510638 (1265 1510);
PAINT MONO (1265 1510);
FORCEPROP 0 LASTPIN (1275 1400) $PN D2
J 2
(1265 1410);
DISPLAY 0.510638 (1265 1410);
PAINT MONO (1265 1410);
FORCEPROP 0 LASTPIN (1275 1600) $PN A2
J 2
(1265 1610);
DISPLAY 0.510638 (1265 1610);
PAINT MONO (1265 1610);
FORCEPROP 1 LAST PATH I69
J 0
(1925 950);
DISPLAY 0.723404 (1925 950);
PAINT GREEN (1925 950);
DISPLAY INVISIBLE (1925 950);
FORCEPROP 1 LAST CDS_LMAN_SYM_OUTLINE -250,550,250,-550
J 0
(1675 1500);
DISPLAY 0.468085 (1675 1500);
PAINT GREEN (1675 1500);
DISPLAY INVISIBLE (1675 1500);
FORCEPROP 2 LAST CDS_LIB pure_quanta
J 0
(1675 1500);
DISPLAY INVISIBLE (1675 1500);
FORCEPROP 1 LAST PIN_NAMES_ROTATE TRUE
J 0
(1675 1500);
DISPLAY 0.489362 (1675 1500);
PAINT GREEN (1675 1500);
DISPLAY INVISIBLE (1675 1500);
FORCEPROP 0 LAST $SEC 1
J 0
(1425 2375);
DISPLAY 0.680851 (1425 2375);
PAINT MONO (1425 2375);
DISPLAY INVISIBLE (1425 2375);
FORCEPROP 0 LAST CDS_SEC 1
J 0
(1425 2375);
DISPLAY 1.021277 (1425 2375);
DISPLAY INVISIBLE (1425 2375);
FORCEADD Q_CAP..1
(-250 -2150);
FORCEPROP 1 LAST PART_NUMBER CH1566K1B09
J 0
(-200 -2200);
DISPLAY 0.510638 (-200 -2200);
DISPLAY INVISIBLE (-200 -2200);
FORCEPROP 1 LAST VOLTAGE 50V
J 0
(-200 -2150);
DISPLAY 0.510638 (-200 -2150);
FORCEPROP 2 LAST ROOM SCM_P12V_BOM2
J 0
(-200 -2050);
DISPLAY 0.510638 (-200 -2050);
FORCEPROP 1 LAST VALUE 560PF
J 0
(-200 -2125);
DISPLAY 0.510638 (-200 -2125);
FORCEPROP 1 LAST PACK_TYPE C0402
J 0
(-200 -2225);
DISPLAY 0.510638 (-200 -2225);
FORCEPROP 1 LAST MATERIAL X7R
J 0
(-200 -2175);
DISPLAY 0.510638 (-200 -2175);
FORCEPROP 1 LAST LOCATION PC2340
J 0
(-200 -2100);
DISPLAY 0.510638 (-200 -2100);
FORCEPROP 1 LASTPIN (-250 -2050) $PN 1
J 0
(-240 -2070);
DISPLAY 0.510638 (-240 -2070);
PAINT MONO (-240 -2070);
FORCEPROP 1 LASTPIN (-250 -2250) $PN 2
J 0
(-240 -2270);
DISPLAY 0.510638 (-240 -2270);
PAINT MONO (-240 -2270);
FORCEPROP 1 LAST PATH I7
J 0
(-200 -2000);
DISPLAY 0.978723 (-200 -2000);
PAINT WHITE (-200 -2000);
DISPLAY INVISIBLE (-200 -2000);
FORCEPROP 1 LAST TOLERANCE 10%
J 0
(-200 -2200);
DISPLAY 0.638298 (-200 -2200);
DISPLAY INVISIBLE (-200 -2200);
FORCEPROP 2 LAST CDS_LIB pure_quanta
J 0
(-250 -2150);
DISPLAY INVISIBLE (-250 -2150);
FORCEPROP 0 LAST $SEC 1
J 0
(-200 -2050);
DISPLAY 0.680851 (-200 -2050);
PAINT MONO (-200 -2050);
DISPLAY INVISIBLE (-200 -2050);
FORCEPROP 0 LAST CDS_SEC 1
J 0
(-200 -2050);
DISPLAY 1.021277 (-200 -2050);
DISPLAY INVISIBLE (-200 -2050);
FORCEADD Q_RES..2
(400 2225);
FORCEPROP 1 LAST PART_NUMBER CS01002FB07
J 0
(450 2175);
DISPLAY 0.510638 (450 2175);
DISPLAY INVISIBLE (450 2175);
FORCEPROP 1 LAST PACK_TYPE 0402LF
J 0
(450 2150);
DISPLAY 0.510638 (450 2150);
FORCEPROP 1 LAST WATTAGE 1/16W
J 0
(450 2225);
DISPLAY 0.510638 (450 2225);
FORCEPROP 1 LAST VALUE 10
J 0
(450 2275);
DISPLAY 0.510638 (450 2275);
FORCEPROP 1 LAST TOLERANCE 1%
J 0
(450 2250);
DISPLAY 0.510638 (450 2250);
FORCEPROP 1 LAST MATERIAL EMPTY
J 0
(450 2200);
DISPLAY 0.510638 (450 2200);
PAINT RED (450 2200);
FORCEPROP 2 LAST ROOM SCM_P12V_BOM1
J 0
(450 2350);
DISPLAY 0.510638 (450 2350);
FORCEPROP 1 LAST LOCATION PR4003
J 0
(450 2300);
DISPLAY 0.510638 (450 2300);
FORCEPROP 1 LASTPIN (400 2325) $PN 1
J 0
(405 2287);
DISPLAY 0.510638 (405 2287);
PAINT MONO (405 2287);
FORCEPROP 1 LASTPIN (400 2125) $PN 2
J 0
(405 2135);
DISPLAY 0.510638 (405 2135);
PAINT MONO (405 2135);
FORCEPROP 1 LAST PATH I70
J 0
(450 2400);
DISPLAY 0.978723 (450 2400);
PAINT WHITE (450 2400);
DISPLAY INVISIBLE (450 2400);
FORCEPROP 2 LAST CDS_LIB pure_quanta
J 0
(400 2225);
DISPLAY INVISIBLE (400 2225);
FORCEPROP 0 LAST $SEC 1
J 0
(450 2350);
DISPLAY 0.680851 (450 2350);
PAINT MONO (450 2350);
DISPLAY INVISIBLE (450 2350);
FORCEPROP 0 LAST CDS_SEC 1
J 0
(450 2350);
DISPLAY 1.021277 (450 2350);
DISPLAY INVISIBLE (450 2350);
FORCEADD GND..1
(2400 750);
FORCEPROP 3 LASTPIN (2400 800) SIG_NAME GND\g
J 0
(2410 810);
DISPLAY 0.659574 (2410 810);
PAINT MONO (2410 810);
DISPLAY INVISIBLE (2410 810);
FORCEPROP 1 LAST PATH I71
J 0
(2475 750);
DISPLAY 0.872340 (2475 750);
PAINT AQUA (2475 750);
DISPLAY INVISIBLE (2475 750);
FORCEPROP 2 LAST CDS_LIB logical_power
J 0
(2400 750);
DISPLAY INVISIBLE (2400 750);
FORCEPROP 1 LAST SIZE 1B
J 0
(2475 700);
DISPLAY 0.872340 (2475 700);
PAINT GREEN (2475 700);
DISPLAY INVISIBLE (2475 700);
FORCEPROP 1 LAST HDL_POWER GND
J 0
(2400 900);
DISPLAY 0.872340 (2400 900);
PAINT GREEN (2400 900);
DISPLAY INVISIBLE (2400 900);
FORCEADD Q_RES..2
(2525 1125);
FORCEPROP 1 LAST PART_NUMBER CS21332FB05
J 0
(2575 1050);
DISPLAY 0.510638 (2575 1050);
DISPLAY INVISIBLE (2575 1050);
FORCEPROP 2 LAST ROOM SCM_P12V_BOM1
J 0
(2575 1225);
DISPLAY 0.510638 (2575 1225);
FORCEPROP 1 LAST VALUE 1.33K
J 0
(2575 1150);
DISPLAY 0.510638 (2575 1150);
FORCEPROP 1 LAST WATTAGE 1/16W
J 0
(2575 1100);
DISPLAY 0.510638 (2575 1100);
FORCEPROP 1 LAST PACK_TYPE 0402LF
J 0
(2575 1025);
DISPLAY 0.510638 (2575 1025);
FORCEPROP 1 LAST MATERIAL EMPTY
J 0
(2575 1075);
DISPLAY 0.510638 (2575 1075);
PAINT RED (2575 1075);
FORCEPROP 1 LAST TOLERANCE 1%
J 0
(2575 1125);
DISPLAY 0.510638 (2575 1125);
FORCEPROP 1 LAST LOCATION PR4008
J 0
(2575 1175);
DISPLAY 0.510638 (2575 1175);
FORCEPROP 1 LASTPIN (2525 1225) $PN 1
J 0
(2530 1187);
DISPLAY 0.510638 (2530 1187);
PAINT MONO (2530 1187);
FORCEPROP 1 LASTPIN (2525 1025) $PN 2
J 0
(2530 1035);
DISPLAY 0.510638 (2530 1035);
PAINT MONO (2530 1035);
FORCEPROP 1 LAST PATH I72
J 0
(2575 1300);
DISPLAY 0.978723 (2575 1300);
PAINT WHITE (2575 1300);
DISPLAY INVISIBLE (2575 1300);
FORCEPROP 2 LAST CDS_LIB pure_quanta
J 0
(2525 1125);
DISPLAY INVISIBLE (2525 1125);
FORCEPROP 0 LAST $SEC 1
J 0
(2575 1300);
DISPLAY 0.680851 (2575 1300);
PAINT MONO (2575 1300);
DISPLAY INVISIBLE (2575 1300);
FORCEPROP 0 LAST CDS_SEC 1
J 0
(2575 1300);
DISPLAY 1.021277 (2575 1300);
DISPLAY INVISIBLE (2575 1300);
FORCEADD Q_CAP..1
(2475 1825);
FORCEPROP 1 LAST PART_NUMBER CH31006KB18
J 0
(2525 1775);
DISPLAY 0.510638 (2525 1775);
DISPLAY INVISIBLE (2525 1775);
FORCEPROP 1 LAST VOLTAGE 50V
J 0
(2525 1825);
DISPLAY 0.510638 (2525 1825);
FORCEPROP 1 LAST VALUE 0.01UF
J 0
(2525 1850);
DISPLAY 0.510638 (2525 1850);
FORCEPROP 1 LAST MATERIAL EMPTY
J 0
(2525 1800);
DISPLAY 0.510638 (2525 1800);
PAINT RED (2525 1800);
FORCEPROP 1 LAST PACK_TYPE C0402
J 0
(2525 1750);
DISPLAY 0.510638 (2525 1750);
FORCEPROP 1 LAST LOCATION PC2236
J 0
(2525 1875);
DISPLAY 0.510638 (2525 1875);
FORCEPROP 1 LASTPIN (2475 1925) $PN 1
J 0
(2485 1905);
DISPLAY 0.510638 (2485 1905);
PAINT MONO (2485 1905);
FORCEPROP 1 LASTPIN (2475 1725) $PN 2
J 0
(2485 1705);
DISPLAY 0.510638 (2485 1705);
PAINT MONO (2485 1705);
FORCEPROP 1 LAST PATH I73
J 0
(2525 1975);
DISPLAY 0.978723 (2525 1975);
PAINT WHITE (2525 1975);
DISPLAY INVISIBLE (2525 1975);
FORCEPROP 2 LAST CDS_LIB pure_quanta
J 0
(2475 1825);
DISPLAY INVISIBLE (2475 1825);
FORCEPROP 1 LAST TOLERANCE 10%
J 0
(2525 1775);
DISPLAY 0.638298 (2525 1775);
DISPLAY INVISIBLE (2525 1775);
FORCEPROP 0 LAST $SEC 1
J 0
(2525 1975);
DISPLAY 0.680851 (2525 1975);
PAINT MONO (2525 1975);
DISPLAY INVISIBLE (2525 1975);
FORCEPROP 0 LAST CDS_SEC 1
J 0
(2525 1975);
DISPLAY 1.021277 (2525 1975);
DISPLAY INVISIBLE (2525 1975);
FORCEADD Q_RES..1
(3150 1500);
FORCEPROP 1 LAST PART_NUMBER CS00002JB13
J 0
(2975 1450);
DISPLAY 0.595745 (2975 1450);
DISPLAY INVISIBLE (2975 1450);
FORCEPROP 1 LAST MATERIAL EMPTY
J 0
(2925 1500);
DISPLAY 0.595745 (2925 1500);
FORCEPROP 1 LAST PACK_TYPE 0402LF
J 0
(3300 1450);
DISPLAY 0.595745 (3300 1450);
FORCEPROP 1 LAST WATTAGE 1/16W
J 2
(2950 1450);
DISPLAY 0.595745 (2950 1450);
FORCEPROP 1 LAST VALUE 0
J 2
(3300 1500);
DISPLAY 0.595745 (3300 1500);
FORCEPROP 2 LAST ROOM SCM_P12V_BOM1
J 0
(2975 1425);
DISPLAY 0.510638 (2975 1425);
FORCEPROP 1 LAST TOLERANCE 5%
J 0
(3325 1500);
DISPLAY 0.595745 (3325 1500);
FORCEPROP 1 LAST LOCATION PR4012
J 0
(2800 1500);
DISPLAY 0.638298 (2800 1500);
FORCEPROP 1 LASTPIN (3050 1500) $PN 1
J 0
(3062 1512);
DISPLAY 0.787234 (3062 1512);
PAINT MONO (3062 1512);
FORCEPROP 1 LASTPIN (3250 1500) $PN 2
J 0
(3212 1512);
DISPLAY 0.787234 (3212 1512);
PAINT MONO (3212 1512);
FORCEPROP 1 LAST PATH I74
J 0
(3100 1650);
DISPLAY 0.978723 (3100 1650);
PAINT WHITE (3100 1650);
DISPLAY INVISIBLE (3100 1650);
FORCEPROP 2 LAST CDS_LIB pure_quanta
J 0
(3150 1500);
DISPLAY INVISIBLE (3150 1500);
FORCEPROP 0 LAST $SEC 1
J 0
(3100 1575);
DISPLAY 0.680851 (3100 1575);
PAINT MONO (3100 1575);
DISPLAY INVISIBLE (3100 1575);
FORCEPROP 0 LAST CDS_SEC 1
J 0
(3100 1575);
DISPLAY 1.021277 (3100 1575);
DISPLAY INVISIBLE (3100 1575);
FORCEADD Q_CAP..1
R 1
(3075 1600);
FORCEPROP 1 LAST PART_NUMBER CH23906KB14
J 0
(3125 1625);
DISPLAY 0.510638 (3125 1625);
DISPLAY INVISIBLE (3125 1625);
FORCEPROP 2 LAST ROOM SCM_P12V_BOM1
J 0
(3125 1725);
DISPLAY 0.510638 (3125 1725);
FORCEPROP 1 LAST PACK_TYPE C0402
J 0
(2850 1550);
DISPLAY 0.510638 (2850 1550);
FORCEPROP 1 LAST VALUE 3900PF
J 0
(2975 1675);
DISPLAY 0.510638 (2975 1675);
FORCEPROP 1 LAST VOLTAGE 50V
J 0
(3175 1675);
DISPLAY 0.510638 (3175 1675);
FORCEPROP 1 LAST LOCATION PC2237
J 0
(2800 1600);
DISPLAY 0.510638 (2800 1600);
FORCEPROP 1 LASTPIN (2975 1600) $PN 1
R 1
J 0
(2995 1610);
DISPLAY 0.510638 (2995 1610);
PAINT MONO (2995 1610);
FORCEPROP 1 LASTPIN (3175 1600) $PN 2
R 1
J 0
(3195 1610);
DISPLAY 0.510638 (3195 1610);
PAINT MONO (3195 1610);
FORCEPROP 1 LAST PATH I75
R 1
J 0
(2925 1650);
DISPLAY 0.978723 (2925 1650);
PAINT WHITE (2925 1650);
DISPLAY INVISIBLE (2925 1650);
FORCEPROP 1 LAST MATERIAL EMPTY
R 1
J 0
(3075 1650);
DISPLAY 0.638298 (3075 1650);
DISPLAY INVISIBLE (3075 1650);
FORCEPROP 1 LAST TOLERANCE 10%
R 1
J 0
(3125 1650);
DISPLAY 0.638298 (3125 1650);
DISPLAY INVISIBLE (3125 1650);
FORCEPROP 2 LAST CDS_LIB pure_quanta
R 1
J 0
(3075 1600);
DISPLAY INVISIBLE (3075 1600);
FORCEPROP 0 LAST $SEC 1
R 1
J 0
(3175 1725);
DISPLAY 0.680851 (3175 1725);
PAINT MONO (3175 1725);
DISPLAY INVISIBLE (3175 1725);
FORCEPROP 0 LAST CDS_SEC 1
R 1
J 0
(3175 1725);
DISPLAY 1.021277 (3175 1725);
DISPLAY INVISIBLE (3175 1725);
FORCEADD Q_RES..2
(2800 1850);
FORCEPROP 1 LAST PART_NUMBER CS61002FB02
J 0
(2850 1775);
DISPLAY 0.510638 (2850 1775);
DISPLAY INVISIBLE (2850 1775);
FORCEPROP 1 LAST PACK_TYPE 0402LF
J 0
(2850 1750);
DISPLAY 0.510638 (2850 1750);
FORCEPROP 1 LAST WATTAGE 1/16W
J 0
(2850 1825);
DISPLAY 0.510638 (2850 1825);
FORCEPROP 1 LAST VALUE 10M
J 0
(2850 1875);
DISPLAY 0.510638 (2850 1875);
FORCEPROP 2 LAST ROOM SCM_P12V_BOM1
J 0
(2850 1950);
DISPLAY 0.510638 (2850 1950);
FORCEPROP 1 LAST TOLERANCE 1%
J 0
(2850 1850);
DISPLAY 0.510638 (2850 1850);
FORCEPROP 1 LAST MATERIAL EMPTY
J 0
(2850 1800);
DISPLAY 0.510638 (2850 1800);
PAINT RED (2850 1800);
FORCEPROP 1 LAST LOCATION PR4526
J 0
(2850 1900);
DISPLAY 0.510638 (2850 1900);
FORCEPROP 1 LASTPIN (2800 1950) $PN 1
J 0
(2805 1912);
DISPLAY 0.510638 (2805 1912);
PAINT MONO (2805 1912);
FORCEPROP 1 LASTPIN (2800 1750) $PN 2
J 0
(2805 1760);
DISPLAY 0.510638 (2805 1760);
PAINT MONO (2805 1760);
FORCEPROP 1 LAST PATH I76
J 0
(2850 2025);
DISPLAY 0.978723 (2850 2025);
PAINT WHITE (2850 2025);
DISPLAY INVISIBLE (2850 2025);
FORCEPROP 2 LAST CDS_LIB pure_quanta
J 0
(2800 1850);
DISPLAY INVISIBLE (2800 1850);
FORCEPROP 0 LAST $SEC 1
J 0
(2850 2025);
DISPLAY 0.680851 (2850 2025);
PAINT MONO (2850 2025);
DISPLAY INVISIBLE (2850 2025);
FORCEPROP 0 LAST CDS_SEC 1
J 0
(2850 2025);
DISPLAY 1.021277 (2850 2025);
DISPLAY INVISIBLE (2850 2025);
FORCEADD Q_RES..1
(3225 1400);
FORCEPROP 1 LAST PART_NUMBER CS00002JB13
J 0
(3050 1350);
DISPLAY 0.595745 (3050 1350);
DISPLAY INVISIBLE (3050 1350);
FORCEPROP 1 LAST MATERIAL EMPTY
J 0
(3000 1400);
DISPLAY 0.595745 (3000 1400);
FORCEPROP 2 LAST ROOM SCM_P12V_BOM1
J 0
(3050 1325);
DISPLAY 0.510638 (3050 1325);
FORCEPROP 1 LAST VALUE 0
J 2
(3375 1400);
DISPLAY 0.595745 (3375 1400);
FORCEPROP 1 LAST TOLERANCE 5%
J 0
(3400 1400);
DISPLAY 0.595745 (3400 1400);
FORCEPROP 1 LAST PACK_TYPE 0402LF
J 0
(3375 1350);
DISPLAY 0.595745 (3375 1350);
FORCEPROP 1 LAST WATTAGE 1/16W
J 2
(3025 1350);
DISPLAY 0.595745 (3025 1350);
FORCEPROP 1 LAST $LOCATION R4708
J 0
(2875 1400);
DISPLAY 0.638298 (2875 1400);
FORCEPROP 1 LASTPIN (3125 1400) $PN 1
J 0
(3137 1412);
DISPLAY 0.787234 (3137 1412);
PAINT MONO (3137 1412);
FORCEPROP 1 LASTPIN (3325 1400) $PN 2
J 0
(3287 1412);
DISPLAY 0.787234 (3287 1412);
PAINT MONO (3287 1412);
FORCEPROP 1 LAST PATH I77
J 0
(3175 1550);
DISPLAY 0.978723 (3175 1550);
PAINT WHITE (3175 1550);
DISPLAY INVISIBLE (3175 1550);
FORCEPROP 2 LAST CDS_LIB pure_quanta
J 0
(3225 1400);
DISPLAY INVISIBLE (3225 1400);
FORCEPROP 0 LAST CDS_LOCATION R4708
J 0
(3400 1450);
DISPLAY 1.021277 (3400 1450);
DISPLAY INVISIBLE (3400 1450);
FORCEPROP 0 LAST $SEC 1
J 0
(3400 1450);
DISPLAY 0.680851 (3400 1450);
PAINT MONO (3400 1450);
DISPLAY INVISIBLE (3400 1450);
FORCEPROP 0 LAST CDS_SEC 1
J 0
(3400 1450);
DISPLAY 1.021277 (3400 1450);
DISPLAY INVISIBLE (3400 1450);
FORCEADD GND..1
(3275 1550);
FORCEPROP 3 LASTPIN (3275 1600) SIG_NAME GND\g
J 0
(3285 1610);
DISPLAY 0.659574 (3285 1610);
PAINT MONO (3285 1610);
DISPLAY INVISIBLE (3285 1610);
FORCEPROP 1 LAST PATH I78
J 0
(3350 1550);
DISPLAY 0.872340 (3350 1550);
PAINT AQUA (3350 1550);
DISPLAY INVISIBLE (3350 1550);
FORCEPROP 2 LAST CDS_LIB logical_power
J 0
(3275 1550);
DISPLAY INVISIBLE (3275 1550);
FORCEPROP 1 LAST SIZE 1B
J 0
(3350 1500);
DISPLAY 0.872340 (3350 1500);
PAINT GREEN (3350 1500);
DISPLAY INVISIBLE (3350 1500);
FORCEPROP 1 LAST HDL_POWER GND
J 0
(3275 1700);
DISPLAY 0.872340 (3275 1700);
PAINT GREEN (3275 1700);
DISPLAY INVISIBLE (3275 1700);
FORCEADD Q_RES..2
(3500 1750);
FORCEPROP 1 LAST PART_NUMBER CS41002FB09
J 0
(3540 1625);
DISPLAY 0.510638 (3540 1625);
DISPLAY INVISIBLE (3540 1625);
FORCEPROP 2 LAST ROOM SCM_P12V_BOM1
J 0
(3550 1925);
DISPLAY 0.510638 (3550 1925);
FORCEPROP 1 LAST WATTAGE 1/16W
J 0
(3540 1725);
DISPLAY 0.510638 (3540 1725);
FORCEPROP 1 LAST MATERIAL EMPTY
J 0
(3540 1675);
DISPLAY 0.510638 (3540 1675);
FORCEPROP 1 LAST PACK_TYPE 0402LF
J 0
(3540 1575);
DISPLAY 0.510638 (3540 1575);
FORCEPROP 1 LAST VALUE 100K
J 0
(3545 1825);
DISPLAY 0.510638 (3545 1825);
FORCEPROP 1 LAST TOLERANCE 1%
J 0
(3545 1775);
DISPLAY 0.510638 (3545 1775);
FORCEPROP 1 LAST LOCATION R4013
J 0
(3545 1875);
DISPLAY 0.638298 (3545 1875);
FORCEPROP 1 LASTPIN (3500 1850) $PN 1
J 0
(3505 1812);
DISPLAY 0.787234 (3505 1812);
PAINT MONO (3505 1812);
FORCEPROP 1 LASTPIN (3500 1650) $PN 2
J 0
(3505 1660);
DISPLAY 0.787234 (3505 1660);
PAINT MONO (3505 1660);
FORCEPROP 1 LAST PATH I79
J 0
(3550 1925);
DISPLAY 0.978723 (3550 1925);
PAINT WHITE (3550 1925);
DISPLAY INVISIBLE (3550 1925);
FORCEPROP 2 LAST CDS_LIB pure_quanta
J 0
(3500 1750);
DISPLAY INVISIBLE (3500 1750);
FORCEPROP 0 LAST $SEC 1
J 0
(3550 1925);
DISPLAY 0.680851 (3550 1925);
PAINT MONO (3550 1925);
DISPLAY INVISIBLE (3550 1925);
FORCEPROP 0 LAST CDS_SEC 1
J 0
(3550 1925);
DISPLAY 1.021277 (3550 1925);
DISPLAY INVISIBLE (3550 1925);
FORCEADD Q_CAP..1
(-1125 -1750);
FORCEPROP 1 LAST PART_NUMBER CH4223K1B00
J 0
(-1075 -1800);
DISPLAY 0.510638 (-1075 -1800);
DISPLAY INVISIBLE (-1075 -1800);
FORCEPROP 2 LAST ROOM SCM_P12V_BOM2
J 0
(-1075 -1650);
DISPLAY 0.510638 (-1075 -1650);
FORCEPROP 1 LAST MATERIAL X7R
J 0
(-1075 -1775);
DISPLAY 0.510638 (-1075 -1775);
FORCEPROP 1 LAST PACK_TYPE 0402
J 0
(-1075 -1825);
DISPLAY 0.510638 (-1075 -1825);
FORCEPROP 1 LAST VALUE 0.22UF
J 0
(-1075 -1725);
DISPLAY 0.510638 (-1075 -1725);
FORCEPROP 1 LAST VOLTAGE 16V
J 0
(-1075 -1750);
DISPLAY 0.510638 (-1075 -1750);
FORCEPROP 1 LAST LOCATION PC2229
J 0
(-1075 -1700);
DISPLAY 0.510638 (-1075 -1700);
FORCEPROP 1 LAST PATH I8
J 0
(-1075 -1600);
DISPLAY 0.978723 (-1075 -1600);
PAINT WHITE (-1075 -1600);
DISPLAY INVISIBLE (-1075 -1600);
FORCEPROP 1 LAST TOLERANCE 10%
J 0
(-1075 -1800);
DISPLAY 0.638298 (-1075 -1800);
DISPLAY INVISIBLE (-1075 -1800);
FORCEPROP 2 LAST CDS_LIB pure_quanta
J 0
(-1125 -1750);
DISPLAY INVISIBLE (-1125 -1750);
FORCEPROP 0 LAST $SEC 1
J 0
(-1075 -1600);
DISPLAY INVISIBLE (-1075 -1600);
FORCEPROP 0 LAST CDS_SEC 1
J 0
(-1075 -1600);
DISPLAY INVISIBLE (-1075 -1600);
FORCEPROP 1 LASTPIN (-1125 -1650) $PN 1
J 0
(-1115 -1670);
DISPLAY 0.787234 (-1115 -1670);
PAINT MONO (-1115 -1670);
DISPLAY INVISIBLE (-1115 -1670);
FORCEPROP 1 LASTPIN (-1125 -1850) $PN 2
J 0
(-1115 -1870);
DISPLAY 0.787234 (-1115 -1870);
PAINT MONO (-1115 -1870);
DISPLAY INVISIBLE (-1115 -1870);
FORCEADD VCCAUX15..1
(3700 2100);
FORCEPROP 3 LASTPIN (3700 2050) SIG_NAME P3V3_AUX\g
J 0
(3710 2060);
DISPLAY 0.659574 (3710 2060);
PAINT MONO (3710 2060);
DISPLAY INVISIBLE (3710 2060);
FORCEPROP 1 LAST HDL_POWER P3V3_AUX
J 1
(3700 2150);
DISPLAY 0.723404 (3700 2150);
PAINT GREEN (3700 2150);
FORCEPROP 1 LAST PATH I80
J 0
(3750 2125);
DISPLAY 0.872340 (3750 2125);
PAINT AQUA (3750 2125);
DISPLAY INVISIBLE (3750 2125);
FORCEPROP 2 LAST CDS_LIB logical_power
J 0
(3700 2100);
DISPLAY INVISIBLE (3700 2100);
FORCEADD Q_RES..2
(3925 1750);
FORCEPROP 1 LAST PART_NUMBER CS41002FB09
J 0
(3965 1625);
DISPLAY 0.510638 (3965 1625);
DISPLAY INVISIBLE (3965 1625);
FORCEPROP 1 LAST PACK_TYPE 0402LF
J 0
(3965 1575);
DISPLAY 0.510638 (3965 1575);
FORCEPROP 1 LAST MATERIAL EMPTY
J 0
(3965 1675);
DISPLAY 0.510638 (3965 1675);
FORCEPROP 1 LAST WATTAGE 1/16W
J 0
(3965 1725);
DISPLAY 0.510638 (3965 1725);
FORCEPROP 1 LAST VALUE 100K
J 0
(3970 1825);
DISPLAY 0.510638 (3970 1825);
FORCEPROP 2 LAST ROOM SCM_P12V_BOM1
J 0
(3975 1925);
DISPLAY 0.638298 (3975 1925);
FORCEPROP 1 LAST TOLERANCE 1%
J 0
(3970 1775);
DISPLAY 0.510638 (3970 1775);
FORCEPROP 1 LAST LOCATION R4015
J 0
(3970 1875);
DISPLAY 0.638298 (3970 1875);
FORCEPROP 1 LASTPIN (3925 1850) $PN 1
J 0
(3930 1812);
DISPLAY 0.787234 (3930 1812);
PAINT MONO (3930 1812);
FORCEPROP 1 LASTPIN (3925 1650) $PN 2
J 0
(3930 1660);
DISPLAY 0.787234 (3930 1660);
PAINT MONO (3930 1660);
FORCEPROP 1 LAST PATH I81
J 0
(3975 1925);
DISPLAY 0.978723 (3975 1925);
PAINT WHITE (3975 1925);
DISPLAY INVISIBLE (3975 1925);
FORCEPROP 2 LAST CDS_LIB pure_quanta
J 0
(3925 1750);
DISPLAY INVISIBLE (3925 1750);
FORCEPROP 0 LAST $SEC 1
J 0
(3975 1925);
DISPLAY 0.680851 (3975 1925);
PAINT MONO (3975 1925);
DISPLAY INVISIBLE (3975 1925);
FORCEPROP 0 LAST CDS_SEC 1
J 0
(3975 1925);
DISPLAY 1.021277 (3975 1925);
DISPLAY INVISIBLE (3975 1925);
FORCEADD SCHOTTKY_AC..1
R 1
(2900 2450);
FORCEPROP 1 LAST PART_NUMBER BC000340Z30
J 0
(2950 2375);
DISPLAY 0.510638 (2950 2375);
PAINT GREEN (2950 2375);
DISPLAY INVISIBLE (2950 2375);
FORCEPROP 2 LAST VALUE B340A-13-F
J 0
(2950 2425);
DISPLAY 0.510638 (2950 2425);
FORCEPROP 1 LAST MATERIAL IC
J 0
(2950 2350);
DISPLAY 0.510638 (2950 2350);
PAINT GREEN (2950 2350);
FORCEPROP 1 LAST LOCATION PD116
J 0
(2950 2475);
DISPLAY 0.510638 (2950 2475);
PAINT GREEN (2950 2475);
FORCEPROP 0 LASTPIN (2900 2325) $PN A
R 1
J 2
(2890 2360);
DISPLAY 0.510638 (2890 2360);
FORCEPROP 0 LASTPIN (2900 2575) $PN C
R 1
J 0
(2890 2535);
DISPLAY 0.510638 (2890 2535);
FORCEPROP 1 LAST PATH I82
R 1
J 0
(2900 2450);
DISPLAY 0.723404 (2900 2450);
PAINT GREEN (2900 2450);
DISPLAY INVISIBLE (2900 2450);
FORCEPROP 2 LAST CDS_LIB pure_quanta
R 1
J 0
(2900 2450);
DISPLAY INVISIBLE (2900 2450);
FORCEPROP 1 LAST CDS_LMAN_SYM_OUTLINE -75,50,75,-50
R 1
J 0
(2900 2450);
DISPLAY 0.468085 (2900 2450);
PAINT GREEN (2900 2450);
DISPLAY INVISIBLE (2900 2450);
FORCEPROP 1 LAST NEEDS_NO_SIZE TRUE
R 1
J 0
(2950 2525);
DISPLAY 0.468085 (2950 2525);
PAINT GREEN (2950 2525);
DISPLAY INVISIBLE (2950 2525);
FORCEPROP 0 LAST PART_TYPE SMLF
J 0
(2950 2625);
DISPLAY 1.021277 (2950 2625);
DISPLAY INVISIBLE (2950 2625);
FORCEPROP 0 LAST $SEC 1
R 1
J 0
(2950 2525);
DISPLAY INVISIBLE (2950 2525);
FORCEPROP 0 LAST CDS_SEC 1
R 1
J 0
(2950 2525);
DISPLAY INVISIBLE (2950 2525);
FORCEADD Q_CAP..1
(3375 2425);
FORCEPROP 1 LAST PART_NUMBER CH4104K1B00
J 0
(3425 2325);
DISPLAY 0.510638 (3425 2325);
DISPLAY INVISIBLE (3425 2325);
FORCEPROP 1 LAST PACK_TYPE 0402
J 0
(3425 2275);
DISPLAY 0.510638 (3425 2275);
FORCEPROP 1 LAST VALUE 0.1UF
J 0
(3425 2475);
DISPLAY 0.510638 (3425 2475);
FORCEPROP 1 LAST VOLTAGE 25V
J 0
(3425 2425);
DISPLAY 0.510638 (3425 2425);
FORCEPROP 1 LAST MATERIAL X7R
J 0
(3425 2375);
DISPLAY 0.510638 (3425 2375);
FORCEPROP 1 LAST LOCATION PC2238
J 0
(3425 2525);
DISPLAY 0.510638 (3425 2525);
FORCEPROP 1 LASTPIN (3375 2525) $PN 1
J 0
(3385 2505);
DISPLAY 0.510638 (3385 2505);
PAINT MONO (3385 2505);
FORCEPROP 1 LASTPIN (3375 2325) $PN 2
J 0
(3385 2305);
DISPLAY 0.510638 (3385 2305);
PAINT MONO (3385 2305);
FORCEPROP 1 LAST PATH I83
J 0
(3425 2575);
DISPLAY 0.978723 (3425 2575);
PAINT WHITE (3425 2575);
DISPLAY INVISIBLE (3425 2575);
FORCEPROP 2 LAST CDS_LIB pure_quanta
J 0
(3375 2425);
DISPLAY INVISIBLE (3375 2425);
FORCEPROP 1 LAST TOLERANCE 10%
J 0
(3425 2375);
DISPLAY 0.978723 (3425 2375);
DISPLAY INVISIBLE (3425 2375);
FORCEPROP 0 LAST $SEC 1
J 0
(3425 2575);
DISPLAY 0.680851 (3425 2575);
PAINT MONO (3425 2575);
DISPLAY INVISIBLE (3425 2575);
FORCEPROP 0 LAST CDS_SEC 1
J 0
(3425 2575);
DISPLAY 1.021277 (3425 2575);
DISPLAY INVISIBLE (3425 2575);
FORCEADD Q_CAP..1
(3800 2425);
FORCEPROP 1 LAST PART_NUMBER CH6103KEA03
J 0
(3850 2325);
DISPLAY 0.510638 (3850 2325);
DISPLAY INVISIBLE (3850 2325);
FORCEPROP 1 LAST MATERIAL X6S
J 0
(3850 2375);
DISPLAY 0.510638 (3850 2375);
FORCEPROP 1 LAST VALUE 10UF
J 0
(3850 2475);
DISPLAY 0.510638 (3850 2475);
FORCEPROP 1 LAST VOLTAGE 16V
J 0
(3850 2425);
DISPLAY 0.510638 (3850 2425);
FORCEPROP 1 LAST PACK_TYPE C0805
J 0
(3850 2275);
DISPLAY 0.510638 (3850 2275);
FORCEPROP 1 LAST LOCATION PC2240
J 0
(3850 2525);
DISPLAY 0.510638 (3850 2525);
FORCEPROP 1 LAST PATH I84
J 0
(3850 2575);
DISPLAY 0.978723 (3850 2575);
PAINT WHITE (3850 2575);
DISPLAY INVISIBLE (3850 2575);
FORCEPROP 2 LAST CDS_LIB pure_quanta
J 0
(3800 2425);
DISPLAY INVISIBLE (3800 2425);
FORCEPROP 1 LAST TOLERANCE 10%
J 0
(3850 2375);
DISPLAY 0.978723 (3850 2375);
DISPLAY INVISIBLE (3850 2375);
FORCEPROP 0 LAST $SEC 1
J 0
(3850 2575);
DISPLAY INVISIBLE (3850 2575);
FORCEPROP 0 LAST CDS_SEC 1
J 0
(3850 2575);
DISPLAY INVISIBLE (3850 2575);
FORCEPROP 1 LASTPIN (3800 2525) $PN 1
J 0
(3810 2505);
DISPLAY 0.787234 (3810 2505);
PAINT MONO (3810 2505);
DISPLAY INVISIBLE (3810 2505);
FORCEPROP 1 LASTPIN (3800 2325) $PN 2
J 0
(3810 2305);
DISPLAY 0.787234 (3810 2305);
PAINT MONO (3810 2305);
DISPLAY INVISIBLE (3810 2305);
FORCEADD OFFPAGE..2
(4325 1400);
PAINT AQUA (4325 1400);
FORCEPROP 2 LAST $XR1 255 
J 0
(4514 1364);
DISPLAY 0.638298 (4514 1364);
PAINT MONO (4514 1364);
FORCEPROP 2 LAST $XR0 242 
J 0
(4514 1400);
DISPLAY 0.638298 (4514 1400);
PAINT MONO (4514 1400);
FORCEPROP 2 LAST PATH I85
J 0
(4525 1450);
DISPLAY 1.021277 (4525 1450);
DISPLAY INVISIBLE (4525 1450);
FORCEPROP 2 LAST CDS_LIB standard
J 0
(4325 1400);
DISPLAY INVISIBLE (4325 1400);
FORCEPROP 1 LAST COMMENT_BODY TRUE
J 0
(4280 1305);
DISPLAY 0.872340 (4280 1305);
PAINT GREEN (4280 1305);
DISPLAY INVISIBLE (4280 1305);
FORCEPROP 1 LAST OFFPAGE TRUE
J 0
(4650 1275);
DISPLAY 0.872340 (4650 1275);
PAINT AQUA (4650 1275);
DISPLAY INVISIBLE (4650 1275);
FORCEADD OFFPAGE..2
(4325 1500);
PAINT AQUA (4325 1500);
FORCEPROP 2 LAST $XR1 216 
J 0
(4514 1464);
DISPLAY 0.638298 (4514 1464);
PAINT MONO (4514 1464);
FORCEPROP 2 LAST $XR0 242 
J 0
(4514 1500);
DISPLAY 0.638298 (4514 1500);
PAINT MONO (4514 1500);
FORCEPROP 2 LAST PATH I86
J 0
(4525 1550);
DISPLAY 1.021277 (4525 1550);
DISPLAY INVISIBLE (4525 1550);
FORCEPROP 2 LAST CDS_LIB standard
J 0
(4325 1500);
DISPLAY INVISIBLE (4325 1500);
FORCEPROP 1 LAST OFFPAGE TRUE
J 0
(4650 1375);
DISPLAY 0.872340 (4650 1375);
PAINT AQUA (4650 1375);
DISPLAY INVISIBLE (4650 1375);
FORCEPROP 1 LAST COMMENT_BODY TRUE
J 0
(4280 1405);
DISPLAY 0.872340 (4280 1405);
PAINT GREEN (4280 1405);
DISPLAY INVISIBLE (4280 1405);
FORCEADD GND..1
(4200 2125);
FORCEPROP 3 LASTPIN (4200 2175) SIG_NAME GND\g
J 0
(4210 2185);
DISPLAY 0.659574 (4210 2185);
PAINT MONO (4210 2185);
DISPLAY INVISIBLE (4210 2185);
FORCEPROP 1 LAST PATH I87
J 0
(4275 2125);
DISPLAY 0.872340 (4275 2125);
PAINT AQUA (4275 2125);
DISPLAY INVISIBLE (4275 2125);
FORCEPROP 1 LAST SIZE 1B
J 0
(4275 2075);
DISPLAY 0.872340 (4275 2075);
PAINT GREEN (4275 2075);
DISPLAY INVISIBLE (4275 2075);
FORCEPROP 2 LAST CDS_LIB logical_power
J 0
(4200 2125);
DISPLAY INVISIBLE (4200 2125);
FORCEPROP 1 LAST HDL_POWER GND
J 0
(4200 2275);
DISPLAY 0.872340 (4200 2275);
PAINT GREEN (4200 2275);
DISPLAY INVISIBLE (4200 2275);
FORCEADD Q_CAP..1
(4200 2425);
FORCEPROP 1 LAST PART_NUMBER CH6223MEA03
J 0
(4250 2325);
DISPLAY 0.510638 (4250 2325);
DISPLAY INVISIBLE (4250 2325);
FORCEPROP 1 LAST VOLTAGE 16V
J 0
(4250 2425);
DISPLAY 0.510638 (4250 2425);
FORCEPROP 1 LAST VALUE 22UF
J 0
(4250 2475);
DISPLAY 0.510638 (4250 2475);
FORCEPROP 1 LAST MATERIAL X6S
J 0
(4250 2375);
DISPLAY 0.510638 (4250 2375);
FORCEPROP 1 LAST PACK_TYPE C0805
J 0
(4250 2275);
DISPLAY 0.510638 (4250 2275);
FORCEPROP 1 LAST LOCATION PC2242
J 0
(4250 2525);
DISPLAY 0.510638 (4250 2525);
FORCEPROP 1 LAST PATH I88
J 0
(4250 2575);
DISPLAY 0.978723 (4250 2575);
PAINT WHITE (4250 2575);
DISPLAY INVISIBLE (4250 2575);
FORCEPROP 2 LAST CDS_LIB pure_quanta
J 0
(4200 2425);
DISPLAY INVISIBLE (4200 2425);
FORCEPROP 1 LAST TOLERANCE 20%
J 0
(3989 2385);
DISPLAY 0.787234 (3989 2385);
PAINT GREEN (3989 2385);
DISPLAY INVISIBLE (3989 2385);
FORCEPROP 0 LAST $SEC 1
J 0
(4250 2575);
DISPLAY INVISIBLE (4250 2575);
FORCEPROP 0 LAST CDS_SEC 1
J 0
(4250 2575);
DISPLAY INVISIBLE (4250 2575);
FORCEPROP 1 LASTPIN (4200 2525) $PN 1
J 0
(4210 2505);
DISPLAY 0.787234 (4210 2505);
PAINT MONO (4210 2505);
DISPLAY INVISIBLE (4210 2505);
FORCEPROP 1 LASTPIN (4200 2325) $PN 2
J 0
(4210 2305);
DISPLAY 0.787234 (4210 2305);
PAINT MONO (4210 2305);
DISPLAY INVISIBLE (4210 2305);
FORCEADD UNIVERSAL_POWER..1
R 2
(4200 2725);
FORCEPROP 3 LASTPIN (4200 2675) SIG_NAME P12V_SCM_R\g
J 0
(4210 2685);
DISPLAY 0.659574 (4210 2685);
PAINT MONO (4210 2685);
DISPLAY INVISIBLE (4210 2685);
FORCEPROP 1 LAST HDL_POWER P12V_SCM_R
J 1
(4225 2775);
DISPLAY 0.510638 (4225 2775);
PAINT GREEN (4225 2775);
FORCEPROP 1 LAST PATH I89
J 2
(4150 2750);
DISPLAY 0.872340 (4150 2750);
PAINT AQUA (4150 2750);
DISPLAY INVISIBLE (4150 2750);
FORCEPROP 2 LAST CDS_LIB logical_power
J 0
(4200 2725);
DISPLAY INVISIBLE (4200 2725);
FORCEADD MOSFET_NCH_GDS_ESD_PROTECTED..1
(-1375 -225);
FORCEPROP 1 LAST PART_NUMBER BAM70020002
J 0
(-1233 -313);
DISPLAY 0.723404 (-1233 -313);
PAINT GREEN (-1233 -313);
DISPLAY INVISIBLE (-1233 -313);
FORCEPROP 2 LAST VALUE 2N7002K
J 0
(-1225 -175);
DISPLAY 0.680851 (-1225 -175);
FORCEPROP 2 LAST PART_TYPE SMLF
J 0
(-1225 -125);
DISPLAY 0.680851 (-1225 -125);
FORCEPROP 1 LAST MATERIAL IC
J 0
(-1233 -370);
DISPLAY 0.723404 (-1233 -370);
PAINT GREEN (-1233 -370);
FORCEPROP 1 LAST $LOCATION Q39
J 0
(-1233 -261);
DISPLAY 0.723404 (-1233 -261);
PAINT GREEN (-1233 -261);
FORCEPROP 0 LASTPIN (-1350 -25) $PN D
R 1
J 0
(-1360 -15);
DISPLAY 0.680851 (-1360 -15);
PAINT MONO (-1360 -15);
FORCEPROP 0 LASTPIN (-1550 -225) $PN G
J 2
(-1560 -215);
DISPLAY 0.680851 (-1560 -215);
PAINT MONO (-1560 -215);
FORCEPROP 0 LASTPIN (-1350 -425) $PN S
R 1
J 2
(-1360 -435);
DISPLAY 0.680851 (-1360 -435);
PAINT MONO (-1360 -435);
FORCEPROP 1 LAST PATH I9
J 0
(-1250 -375);
DISPLAY 0.723404 (-1250 -375);
PAINT GREEN (-1250 -375);
DISPLAY INVISIBLE (-1250 -375);
FORCEPROP 1 LAST NEEDS_NO_SIZE TRUE
J 0
(-1250 -335);
DISPLAY 0.723404 (-1250 -335);
PAINT GREEN (-1250 -335);
DISPLAY INVISIBLE (-1250 -335);
FORCEPROP 2 LAST CDS_LIB pure_quanta
J 0
(-1375 -225);
DISPLAY INVISIBLE (-1375 -225);
FORCEPROP 1 LAST CDS_LMAN_SYM_OUTLINE -125,150,125,-150
J 0
(-1375 -225);
DISPLAY 0.468085 (-1375 -225);
PAINT GREEN (-1375 -225);
DISPLAY INVISIBLE (-1375 -225);
FORCEPROP 0 LAST CDS_LOCATION Q39
J 0
(-1200 -100);
DISPLAY 1.021277 (-1200 -100);
DISPLAY INVISIBLE (-1200 -100);
FORCEPROP 0 LAST $SEC 1
J 0
(-1225 -75);
DISPLAY 0.680851 (-1225 -75);
PAINT MONO (-1225 -75);
DISPLAY INVISIBLE (-1225 -75);
FORCEPROP 0 LAST CDS_SEC 1
J 0
(-1200 -100);
DISPLAY 1.021277 (-1200 -100);
DISPLAY INVISIBLE (-1200 -100);
FORCEADD RS31312R..1
(1025 -1375);
FORCEPROP 1 LAST PART_NUMBER AL031312000
J 0
(778 -711);
DISPLAY 0.723404 (778 -711);
PAINT GREEN (778 -711);
DISPLAY INVISIBLE (778 -711);
FORCEPROP 2 LAST VALUE RS31312R
J 0
(775 -775);
DISPLAY 0.510638 (775 -775);
FORCEPROP 1 LAST MATERIAL IC
J 0
(778 -838);
DISPLAY 0.723404 (778 -838);
PAINT GREEN (778 -838);
FORCEPROP 2 LAST ROOM SCM_P12V_BOM2
J 0
(775 -600);
DISPLAY 0.510638 (775 -600);
FORCEPROP 1 LAST LOCATION PU299
J 0
(778 -564);
DISPLAY 0.723404 (778 -564);
PAINT GREEN (778 -564);
FORCEPROP 0 LASTPIN (1425 -1500) $PN 12
J 0
(1435 -1490);
DISPLAY 0.680851 (1435 -1490);
PAINT MONO (1435 -1490);
FORCEPROP 0 LASTPIN (625 -1250) $PN 1
J 2
(615 -1240);
DISPLAY 0.680851 (615 -1240);
PAINT MONO (615 -1240);
FORCEPROP 0 LASTPIN (625 -1450) $PN 3
J 2
(615 -1440);
DISPLAY 0.680851 (615 -1440);
PAINT MONO (615 -1440);
FORCEPROP 0 LASTPIN (1425 -1750) $PN 9
J 0
(1435 -1740);
DISPLAY 0.680851 (1435 -1740);
PAINT MONO (1435 -1740);
FORCEPROP 0 LASTPIN (625 -1850) $PN 7
J 2
(615 -1840);
DISPLAY 0.680851 (615 -1840);
PAINT MONO (615 -1840);
FORCEPROP 0 LASTPIN (1425 -1850) $PN 8
J 0
(1435 -1840);
DISPLAY 0.680851 (1435 -1840);
PAINT MONO (1435 -1840);
FORCEPROP 0 LASTPIN (625 -1650) $PN 5
J 2
(615 -1640);
DISPLAY 0.680851 (615 -1640);
PAINT MONO (615 -1640);
FORCEPROP 0 LASTPIN (625 -1350) $PN 2
J 2
(615 -1340);
DISPLAY 0.680851 (615 -1340);
PAINT MONO (615 -1340);
FORCEPROP 0 LASTPIN (1425 -1600) $PN 11
J 0
(1435 -1590);
DISPLAY 0.680851 (1435 -1590);
PAINT MONO (1435 -1590);
FORCEPROP 0 LASTPIN (1425 -900) $PN 10
J 0
(1435 -890);
DISPLAY 0.680851 (1435 -890);
PAINT MONO (1435 -890);
FORCEPROP 0 LASTPIN (625 -1750) $PN 6
J 2
(615 -1740);
DISPLAY 0.680851 (615 -1740);
PAINT MONO (615 -1740);
FORCEPROP 0 LASTPIN (625 -1550) $PN 4
J 2
(615 -1540);
DISPLAY 0.680851 (615 -1540);
PAINT MONO (615 -1540);
FORCEPROP 0 LASTPIN (625 -900) $PN 21_22
J 2
(615 -890);
DISPLAY 0.680851 (615 -890);
PAINT MONO (615 -890);
FORCEPROP 0 LASTPIN (625 -950) $PN 23
J 2
(615 -940);
DISPLAY 0.680851 (615 -940);
PAINT MONO (615 -940);
FORCEPROP 0 LASTPIN (625 -1000) $PN 24
J 2
(615 -990);
DISPLAY 0.680851 (615 -990);
PAINT MONO (615 -990);
FORCEPROP 0 LASTPIN (625 -1050) $PN 25
J 2
(615 -1040);
DISPLAY 0.680851 (615 -1040);
PAINT MONO (615 -1040);
FORCEPROP 0 LASTPIN (625 -1100) $PN 26
J 2
(615 -1090);
DISPLAY 0.680851 (615 -1090);
PAINT MONO (615 -1090);
FORCEPROP 0 LASTPIN (1425 -1400) $PN 13
J 0
(1435 -1390);
DISPLAY 0.680851 (1435 -1390);
PAINT MONO (1435 -1390);
FORCEPROP 0 LASTPIN (1425 -1350) $PN 14
J 0
(1435 -1340);
DISPLAY 0.680851 (1435 -1340);
PAINT MONO (1435 -1340);
FORCEPROP 0 LASTPIN (1425 -1300) $PN 15
J 0
(1435 -1290);
DISPLAY 0.680851 (1435 -1290);
PAINT MONO (1435 -1290);
FORCEPROP 0 LASTPIN (1425 -1250) $PN 16
J 0
(1435 -1240);
DISPLAY 0.680851 (1435 -1240);
PAINT MONO (1435 -1240);
FORCEPROP 0 LASTPIN (1425 -1200) $PN 17
J 0
(1435 -1190);
DISPLAY 0.680851 (1435 -1190);
PAINT MONO (1435 -1190);
FORCEPROP 0 LASTPIN (1425 -1150) $PN 18
J 0
(1435 -1140);
DISPLAY 0.680851 (1435 -1140);
PAINT MONO (1435 -1140);
FORCEPROP 0 LASTPIN (1425 -1100) $PN 19
J 0
(1435 -1090);
DISPLAY 0.680851 (1435 -1090);
PAINT MONO (1435 -1090);
FORCEPROP 0 LASTPIN (1425 -1050) $PN 20
J 0
(1435 -1040);
DISPLAY 0.680851 (1435 -1040);
PAINT MONO (1435 -1040);
FORCEPROP 1 LAST PATH I90
J 0
(1025 -1375);
DISPLAY 0.723404 (1025 -1375);
PAINT GREEN (1025 -1375);
DISPLAY INVISIBLE (1025 -1375);
FORCEPROP 0 LAST PART_TYPE SMLF
J 0
(772 -590);
DISPLAY 1.021277 (772 -590);
DISPLAY INVISIBLE (772 -590);
FORCEPROP 2 LAST CDS_LIB pure_quanta
J 0
(1025 -1375);
DISPLAY INVISIBLE (1025 -1375);
FORCEPROP 1 LAST NEEDS_NO_SIZE TRUE
J 0
(1025 -1375);
DISPLAY 0.723404 (1025 -1375);
PAINT GREEN (1025 -1375);
DISPLAY INVISIBLE (1025 -1375);
FORCEPROP 1 LAST CDS_LMAN_SYM_OUTLINE -250,525,250,-525
J 0
(1025 -1375);
DISPLAY 0.468085 (1025 -1375);
PAINT GREEN (1025 -1375);
DISPLAY INVISIBLE (1025 -1375);
FORCEPROP 0 LAST $SEC 1
J 0
(800 -525);
DISPLAY 0.680851 (800 -525);
PAINT MONO (800 -525);
DISPLAY INVISIBLE (800 -525);
FORCEPROP 0 LAST CDS_SEC 1
J 0
(850 -800);
DISPLAY INVISIBLE (850 -800);
FORCEADD Q_RES..1
(2425 -900);
FORCEPROP 1 LAST PART_NUMBER CS00002JB13
J 0
(2250 -950);
DISPLAY 0.595745 (2250 -950);
DISPLAY INVISIBLE (2250 -950);
FORCEPROP 1 LAST VALUE 0
J 2
(2575 -900);
DISPLAY 0.595745 (2575 -900);
FORCEPROP 2 LAST ROOM SCM_P12V_BOM2
J 0
(2250 -975);
DISPLAY 0.510638 (2250 -975);
FORCEPROP 1 LAST MATERIAL CHIP
J 0
(2200 -900);
DISPLAY 0.595745 (2200 -900);
FORCEPROP 1 LAST PACK_TYPE 0402LF
J 0
(2575 -950);
DISPLAY 0.595745 (2575 -950);
FORCEPROP 1 LAST $LOCATION R4770
J 0
(2300 -850);
DISPLAY 0.638298 (2300 -850);
FORCEPROP 1 LASTPIN (2325 -900) $PN 1
J 0
(2337 -888);
DISPLAY 0.787234 (2337 -888);
PAINT MONO (2337 -888);
FORCEPROP 1 LASTPIN (2525 -900) $PN 2
J 0
(2487 -888);
DISPLAY 0.787234 (2487 -888);
PAINT MONO (2487 -888);
FORCEPROP 1 LAST PATH I91
J 0
(2375 -750);
DISPLAY 0.978723 (2375 -750);
PAINT WHITE (2375 -750);
DISPLAY INVISIBLE (2375 -750);
FORCEPROP 2 LAST CDS_LIB pure_quanta
J 0
(2425 -900);
DISPLAY INVISIBLE (2425 -900);
FORCEPROP 1 LAST TOLERANCE 5%
J 0
(2600 -900);
DISPLAY 0.595745 (2600 -900);
DISPLAY INVISIBLE (2600 -900);
FORCEPROP 1 LAST WATTAGE 1/16W
J 2
(2225 -950);
DISPLAY 0.595745 (2225 -950);
DISPLAY INVISIBLE (2225 -950);
FORCEPROP 0 LAST CDS_LOCATION R4770
J 0
(2300 -800);
DISPLAY 1.021277 (2300 -800);
DISPLAY INVISIBLE (2300 -800);
FORCEPROP 0 LAST $SEC 1
J 0
(2300 -800);
DISPLAY 0.680851 (2300 -800);
PAINT MONO (2300 -800);
DISPLAY INVISIBLE (2300 -800);
FORCEPROP 0 LAST CDS_SEC 1
J 0
(2300 -800);
DISPLAY 1.021277 (2300 -800);
DISPLAY INVISIBLE (2300 -800);
FORCEADD Q_RES..2
(2275 -650);
FORCEPROP 1 LAST PART_NUMBER CS31002FB08
J 0
(2350 -700);
DISPLAY 0.510638 (2350 -700);
DISPLAY INVISIBLE (2350 -700);
FORCEPROP 1 LAST PACK_TYPE 0402LF
J 0
(2350 -725);
DISPLAY 0.510638 (2350 -725);
FORCEPROP 1 LAST MATERIAL CHIP
J 0
(2350 -675);
DISPLAY 0.510638 (2350 -675);
PAINT RED (2350 -675);
FORCEPROP 2 LAST ROOM SCM_P12V_BOM2
J 0
(2350 -525);
DISPLAY 0.510638 (2350 -525);
FORCEPROP 1 LAST WATTAGE 1/16W
J 0
(2350 -650);
DISPLAY 0.510638 (2350 -650);
FORCEPROP 1 LAST TOLERANCE 1%
J 0
(2350 -625);
DISPLAY 0.510638 (2350 -625);
FORCEPROP 1 LAST VALUE 10K
J 0
(2350 -600);
DISPLAY 0.510638 (2350 -600);
FORCEPROP 1 LAST LOCATION R3836
J 0
(2350 -575);
DISPLAY 0.638298 (2350 -575);
FORCEPROP 1 LASTPIN (2275 -550) $PN 1
J 0
(2280 -588);
DISPLAY 0.787234 (2280 -588);
PAINT MONO (2280 -588);
FORCEPROP 1 LASTPIN (2275 -750) $PN 2
J 0
(2280 -740);
DISPLAY 0.787234 (2280 -740);
PAINT MONO (2280 -740);
FORCEPROP 2 LAST CDS_LIB pure_quanta
J 0
(2275 -650);
DISPLAY INVISIBLE (2275 -650);
FORCEPROP 1 LAST PATH I92
J 0
(2325 -475);
DISPLAY 0.978723 (2325 -475);
PAINT WHITE (2325 -475);
DISPLAY INVISIBLE (2325 -475);
FORCEPROP 0 LAST $SEC 1
J 0
(2330 -433);
DISPLAY 0.680851 (2330 -433);
PAINT MONO (2330 -433);
DISPLAY INVISIBLE (2330 -433);
FORCEPROP 0 LAST CDS_SEC 1
J 0
(2325 -475);
DISPLAY INVISIBLE (2325 -475);
FORCEADD VCCAUX15..1
(2275 -450);
FORCEPROP 3 LASTPIN (2275 -500) SIG_NAME P3V3_AUX\g
J 0
(2285 -490);
DISPLAY 0.659574 (2285 -490);
PAINT MONO (2285 -490);
DISPLAY INVISIBLE (2285 -490);
FORCEPROP 1 LAST HDL_POWER P3V3_AUX
J 1
(2275 -400);
DISPLAY 0.723404 (2275 -400);
PAINT GREEN (2275 -400);
FORCEPROP 1 LAST PATH I93
J 0
(2325 -425);
DISPLAY 0.872340 (2325 -425);
PAINT AQUA (2325 -425);
DISPLAY INVISIBLE (2325 -425);
FORCEPROP 2 LAST CDS_LIB logical_power
J 0
(2275 -450);
DISPLAY INVISIBLE (2275 -450);
FORCEADD OFFPAGE..2
(3275 -900);
PAINT AQUA (3275 -900);
FORCEPROP 2 LAST $XR1 216 
J 0
(3584 -900);
DISPLAY 0.638298 (3584 -900);
PAINT MONO (3584 -900);
FORCEPROP 2 LAST $XR0 242 
J 0
(3464 -900);
DISPLAY 0.638298 (3464 -900);
PAINT MONO (3464 -900);
FORCEPROP 2 LAST PATH I94
J 0
(3650 -850);
DISPLAY 1.021277 (3650 -850);
DISPLAY INVISIBLE (3650 -850);
FORCEPROP 2 LAST CDS_LIB standard
J 0
(3275 -900);
DISPLAY INVISIBLE (3275 -900);
FORCEPROP 1 LAST OFFPAGE TRUE
J 0
(3600 -1025);
DISPLAY 0.872340 (3600 -1025);
PAINT AQUA (3600 -1025);
DISPLAY INVISIBLE (3600 -1025);
FORCEPROP 1 LAST COMMENT_BODY TRUE
J 0
(3230 -995);
DISPLAY 0.872340 (3230 -995);
PAINT GREEN (3230 -995);
DISPLAY INVISIBLE (3230 -995);
FORCEADD QUANTA_TITLE_BLOCK_C..1
(4675 -3350);
FORCEPROP 0 LAST CDS_CON_LAST_MODIFIED Fri Aug 25 14:04:10 2023
J 0
(2790 -3335);
DISPLAY INVISIBLE (2790 -3335);
FORCEPROP 1 LAST CUSTOM_TXT_CDS <CON_LAST_MODIFIED>
J 0
(2790 -3335);
DISPLAY 0.978723 (2790 -3335);
FORCEPROP 2 LAST CUSTOM_TXT_CDS <XR_PAGE_TITLE>
J 0
(-3215 1900);
DISPLAY 0.638298 (-3215 1900);
PAINT PINK (-3215 1900);
DISPLAY INVISIBLE (-3215 1900);
FORCEPROP 1 LAST CUSTOM_TXT_CDS <NAME_2>
J 0
(1500 -3300);
FORCEPROP 1 LAST CUSTOM_TXT_CDS <NAME_1>
J 0
(1500 -3175);
FORCEPROP 1 LAST CUSTOM_TXT_CDS <Q_NUMBER>
J 0
(3272 -3247);
DISPLAY 1.212766 (3272 -3247);
FORCEPROP 1 LAST CUSTOM_TXT_CDS <Q_PROJ>
J 0
(2293 -3248);
DISPLAY 1.212766 (2293 -3248);
FORCEPROP 1 LAST CUSTOM_TXT_CDS <Q_REV>
J 0
(4491 -3247);
DISPLAY 1.212766 (4491 -3247);
FORCEPROP 1 LAST CUSTOM_TXT_CDS <CON_PAGE_NUM> OF <CON_TOTAL_PAGES>
J 0
(4229 -3332);
DISPLAY 0.978723 (4229 -3332);
FORCEPROP 1 LAST Q_TITLE P12V_SCM
J 0
(-4625 -3300);
DISPLAY 2.446809 (-4625 -3300);
PAINT GREEN (-4625 -3300);
FORCEPROP 1 LAST Q_DEPT 
J 1
(912 -3301);
DISPLAY 1.957447 (912 -3301);
PAINT GREEN (912 -3301);
FORCEPROP 2 LAST CDS_XR_PAGE_TITLE CR-242 : @S9S_MB_2U_LIB.S9S_MB_2U(SCH_1):PAGE242
J 0
(-3215 1900);
DISPLAY 0.638298 (-3215 1900);
PAINT PINK (-3215 1900);
DISPLAY INVISIBLE (-3215 1900);
FORCEPROP 2 LAST PAGE_BORDER TRUE
J 0
(-3215 1900);
DISPLAY 0.638298 (-3215 1900);
PAINT PINK (-3215 1900);
DISPLAY INVISIBLE (-3215 1900);
FORCEPROP 1 LAST COMMENT_BODY TRUE
J 0
(4687 -3363);
DISPLAY 0.978723 (4687 -3363);
PAINT GREEN (4687 -3363);
DISPLAY INVISIBLE (4687 -3363);
FORCEPROP 1 LAST CDS_LMAN_SYM_OUTLINE -9475,6775,100,-125
J 0
(4675 -3350);
DISPLAY 0.468085 (4675 -3350);
PAINT GREEN (4675 -3350);
DISPLAY INVISIBLE (4675 -3350);
FORCEPROP 2 LAST CDS_LIB pure_quanta
J 0
(4675 -3350);
DISPLAY INVISIBLE (4675 -3350);
FORCEADD DNS..2
(3925 1725);
PAINT RED (3925 1725);
FORCEPROP 2 LAST CDS_LIB mstr_misc
J 0
(3925 1725);
DISPLAY INVISIBLE (3925 1725);
FORCEPROP 1 LAST COMMENT_BODY TRUE
R 1
J 0
(4000 1500);
DISPLAY 0.872340 (4000 1500);
PAINT GREEN (4000 1500);
DISPLAY INVISIBLE (4000 1500);
FORCEADD DNS..2
(3500 1725);
PAINT RED (3500 1725);
FORCEPROP 2 LAST CDS_LIB mstr_misc
J 0
(3500 1725);
DISPLAY INVISIBLE (3500 1725);
FORCEPROP 1 LAST COMMENT_BODY TRUE
R 1
J 0
(3575 1500);
DISPLAY 0.872340 (3575 1500);
PAINT GREEN (3575 1500);
DISPLAY INVISIBLE (3575 1500);
FORCEADD DNS..2
(3250 1425);
PAINT RED (3250 1425);
FORCEPROP 2 LAST CDS_LIB mstr_misc
J 0
(3250 1425);
DISPLAY INVISIBLE (3250 1425);
FORCEPROP 1 LAST COMMENT_BODY TRUE
R 1
J 0
(3325 1200);
DISPLAY 0.872340 (3325 1200);
PAINT GREEN (3325 1200);
DISPLAY INVISIBLE (3325 1200);
FORCEADD DNS..2
(2825 1850);
PAINT RED (2825 1850);
FORCEPROP 2 LAST CDS_LIB mstr_misc
J 0
(2825 1850);
DISPLAY INVISIBLE (2825 1850);
FORCEPROP 1 LAST COMMENT_BODY TRUE
R 1
J 0
(2900 1625);
DISPLAY 0.872340 (2900 1625);
PAINT GREEN (2900 1625);
DISPLAY INVISIBLE (2900 1625);
FORCEADD DNS..2
(3175 1500);
PAINT RED (3175 1500);
FORCEPROP 2 LAST CDS_LIB mstr_misc
J 0
(3175 1500);
DISPLAY INVISIBLE (3175 1500);
FORCEPROP 1 LAST COMMENT_BODY TRUE
R 1
J 0
(3250 1275);
DISPLAY 0.872340 (3250 1275);
PAINT GREEN (3250 1275);
DISPLAY INVISIBLE (3250 1275);
FORCEADD DNS..2
(3050 1625);
PAINT RED (3050 1625);
FORCEPROP 2 LAST CDS_LIB mstr_misc
J 0
(3050 1625);
DISPLAY INVISIBLE (3050 1625);
FORCEPROP 1 LAST COMMENT_BODY TRUE
R 1
J 0
(3125 1400);
DISPLAY 0.872340 (3125 1400);
PAINT GREEN (3125 1400);
DISPLAY INVISIBLE (3125 1400);
FORCEADD DNS..2
(2500 1825);
PAINT RED (2500 1825);
FORCEPROP 1 LAST COMMENT_BODY TRUE
R 1
J 0
(2575 1600);
DISPLAY 0.872340 (2575 1600);
PAINT GREEN (2575 1600);
DISPLAY INVISIBLE (2575 1600);
FORCEPROP 2 LAST CDS_LIB mstr_misc
J 0
(2500 1825);
DISPLAY INVISIBLE (2500 1825);
FORCEADD DNS..2
(2550 1100);
PAINT RED (2550 1100);
FORCEPROP 2 LAST CDS_LIB mstr_misc
J 0
(2550 1100);
DISPLAY INVISIBLE (2550 1100);
FORCEPROP 1 LAST COMMENT_BODY TRUE
R 1
J 0
(2625 875);
DISPLAY 0.872340 (2625 875);
PAINT GREEN (2625 875);
DISPLAY INVISIBLE (2625 875);
FORCEADD DNS..2
(425 2225);
PAINT RED (425 2225);
FORCEPROP 2 LAST CDS_LIB mstr_misc
J 0
(425 2225);
DISPLAY INVISIBLE (425 2225);
FORCEPROP 1 LAST COMMENT_BODY TRUE
R 1
J 0
(500 2000);
DISPLAY 0.872340 (500 2000);
PAINT GREEN (500 2000);
DISPLAY INVISIBLE (500 2000);
FORCEADD DNS..2
(1650 1650);
PAINT RED (1650 1650);
FORCEPROP 1 LAST COMMENT_BODY TRUE
R 1
J 0
(1725 1425);
DISPLAY 0.872340 (1725 1425);
PAINT GREEN (1725 1425);
DISPLAY INVISIBLE (1725 1425);
FORCEPROP 2 LAST CDS_LIB mstr_misc
J 0
(1650 1650);
DISPLAY INVISIBLE (1650 1650);
FORCEADD DNS..2
(650 1500);
PAINT RED (650 1500);
FORCEPROP 1 LAST COMMENT_BODY TRUE
R 1
J 0
(725 1275);
DISPLAY 0.872340 (725 1275);
PAINT GREEN (725 1275);
DISPLAY INVISIBLE (725 1275);
FORCEPROP 2 LAST CDS_LIB mstr_misc
J 0
(650 1500);
DISPLAY INVISIBLE (650 1500);
FORCEADD DNS..2
(425 1800);
PAINT RED (425 1800);
FORCEPROP 2 LAST CDS_LIB mstr_misc
J 0
(425 1800);
DISPLAY INVISIBLE (425 1800);
FORCEPROP 1 LAST COMMENT_BODY TRUE
R 1
J 0
(500 1575);
DISPLAY 0.872340 (500 1575);
PAINT GREEN (500 1575);
DISPLAY INVISIBLE (500 1575);
FORCEADD DNS..2
(950 950);
PAINT RED (950 950);
FORCEPROP 2 LAST CDS_LIB mstr_misc
J 0
(950 950);
DISPLAY INVISIBLE (950 950);
FORCEPROP 1 LAST COMMENT_BODY TRUE
R 1
J 0
(1025 725);
DISPLAY 0.872340 (1025 725);
PAINT GREEN (1025 725);
DISPLAY INVISIBLE (1025 725);
FORCEADD DNS..2
(2650 -1275);
PAINT RED (2650 -1275);
FORCEPROP 2 LAST CDS_LIB mstr_misc
J 0
(2650 -1275);
DISPLAY INVISIBLE (2650 -1275);
FORCEPROP 1 LAST COMMENT_BODY TRUE
R 1
J 0
(2725 -1500);
DISPLAY 0.872340 (2725 -1500);
PAINT GREEN (2725 -1500);
DISPLAY INVISIBLE (2725 -1500);
FORCEADD DNS..2
(2050 -1275);
PAINT RED (2050 -1275);
FORCEPROP 2 LAST CDS_LIB mstr_misc
J 0
(2050 -1275);
DISPLAY INVISIBLE (2050 -1275);
FORCEPROP 1 LAST COMMENT_BODY TRUE
R 1
J 0
(2125 -1500);
DISPLAY 0.872340 (2125 -1500);
PAINT GREEN (2125 -1500);
DISPLAY INVISIBLE (2125 -1500);
FORCEADD DNS..2
(100 1925);
PAINT RED (100 1925);
FORCEPROP 2 LAST CDS_LIB mstr_misc
J 0
(100 1925);
DISPLAY INVISIBLE (100 1925);
FORCEPROP 1 LAST COMMENT_BODY TRUE
R 1
J 0
(175 1700);
DISPLAY 0.872340 (175 1700);
PAINT GREEN (175 1700);
DISPLAY INVISIBLE (175 1700);
FORCEADD DNS..2
(100 1225);
PAINT RED (100 1225);
FORCEPROP 2 LAST CDS_LIB mstr_misc
J 0
(100 1225);
DISPLAY INVISIBLE (100 1225);
FORCEPROP 1 LAST COMMENT_BODY TRUE
R 1
J 0
(175 1000);
DISPLAY 0.872340 (175 1000);
PAINT GREEN (175 1000);
DISPLAY INVISIBLE (175 1000);
FORCEADD DNS..2
(-475 1600);
PAINT RED (-475 1600);
FORCEPROP 2 LAST CDS_LIB mstr_misc
J 0
(-475 1600);
DISPLAY INVISIBLE (-475 1600);
FORCEPROP 1 LAST COMMENT_BODY TRUE
R 1
J 0
(-400 1375);
DISPLAY 0.872340 (-400 1375);
PAINT GREEN (-400 1375);
DISPLAY INVISIBLE (-400 1375);
FORCEADD DNS..2
(100 950);
PAINT RED (100 950);
FORCEPROP 2 LAST CDS_LIB mstr_misc
J 0
(100 950);
DISPLAY INVISIBLE (100 950);
FORCEPROP 1 LAST COMMENT_BODY TRUE
R 1
J 0
(175 725);
DISPLAY 0.872340 (175 725);
PAINT GREEN (175 725);
DISPLAY INVISIBLE (175 725);
FORCEADD DNS..2
(-1050 1275);
PAINT RED (-1050 1275);
FORCEPROP 2 LAST CDS_LIB mstr_misc
J 0
(-1050 1275);
DISPLAY INVISIBLE (-1050 1275);
FORCEPROP 1 LAST COMMENT_BODY TRUE
R 1
J 0
(-975 1050);
DISPLAY 0.872340 (-975 1050);
PAINT GREEN (-975 1050);
DISPLAY INVISIBLE (-975 1050);
FORCEADD DNS..2
(-1700 1525);
PAINT RED (-1700 1525);
FORCEPROP 2 LAST CDS_LIB mstr_misc
J 0
(-1700 1525);
DISPLAY INVISIBLE (-1700 1525);
FORCEPROP 1 LAST COMMENT_BODY TRUE
R 1
J 0
(-1625 1300);
DISPLAY 0.872340 (-1625 1300);
PAINT GREEN (-1625 1300);
DISPLAY INVISIBLE (-1625 1300);
FORCEADD DNS..2
(-1725 900);
PAINT RED (-1725 900);
FORCEPROP 2 LAST CDS_LIB mstr_misc
J 0
(-1725 900);
DISPLAY INVISIBLE (-1725 900);
FORCEPROP 1 LAST COMMENT_BODY TRUE
R 1
J 0
(-1650 675);
DISPLAY 0.872340 (-1650 675);
PAINT GREEN (-1650 675);
DISPLAY INVISIBLE (-1650 675);
FORCEADD DNS..2
(-2600 875);
PAINT RED (-2600 875);
FORCEPROP 2 LAST CDS_LIB mstr_misc
J 0
(-2600 875);
DISPLAY INVISIBLE (-2600 875);
FORCEPROP 1 LAST COMMENT_BODY TRUE
R 1
J 0
(-2525 650);
DISPLAY 0.872340 (-2525 650);
PAINT GREEN (-2525 650);
DISPLAY INVISIBLE (-2525 650);
WIRE 16 -1 (4200 2675)(4200 2625);
WIRE 16 -1 (3700 2050)(3700 2000);
WIRE 16 -1 (3900 -700)(3900 -775);
WIRE 16 -1 (150 -550)(150 -650);
WIRE 16 -1 (-500 2525)(-500 2450);
WIRE 16 -1 (-1725 1725)(-1725 1625);
WIRE 16 -1 (-3125 1250)(-3125 1350);
WIRE 16 -1 (-3350 100)(-3350 175);
WIRE 16 -1 (2850 -1750)(2850 -1725);
WIRE 16 -1 (2575 -1750)(2850 -1750);
WIRE 16 -1 (3550 -1100)(3550 -1150);
WIRE 16 -1 (2275 -500)(2275 -550);
WIRE 16 -1 (4200 2175)(4200 2250);
WIRE 16 -1 (3175 1600)(3275 1600);
WIRE 16 -1 (2400 800)(2400 900);
WIRE 16 -1 (400 1500)(400 1475);
WIRE 16 -1 (400 1500)(525 1500);
WIRE 16 -1 (400 1700)(400 1500);
WIRE 16 -1 (925 800)(925 850);
WIRE 16 -1 (75 875)(75 800);
WIRE 16 -1 (3900 -1150)(3900 -1025);
WIRE 16 -1 (3225 -2025)(3225 -2050);
WIRE 16 -1 (3025 -2025)(3225 -2025);
WIRE 16 -1 (3225 -2025)(3550 -2025);
WIRE 16 -1 (2100 -2405)(2100 -2475);
WIRE 16 -1 (1650 -2405)(2100 -2405);
WIRE 16 -1 (2100 -2405)(2100 -2225);
WIRE 16 -1 (566 -1934)(566 -1850);
WIRE 16 -1 (150 -1025)(150 -950);
WIRE 16 -1 (225 -2100)(225 -2025);
WIRE 16 -1 (-500 1900)(-500 1960);
WIRE 16 -1 (-1050 1075)(-1050 1000);
WIRE 16 -1 (-1725 725)(-1725 625);
WIRE 16 -1 (300 -1450)(-175 -1450);
WIRE 16 -1 (300 -1350)(300 -1450);
WIRE 16 -1 (300 -1450)(625 -1450);
WIRE 16 -1 (-1350 -500)(-1350 -425);
WIRE 16 -1 (-250 -2250)(-250 -2325);
WIRE 16 -1 (-675 -2075)(-675 -1925);
WIRE 16 -1 (-1125 -2000)(-1125 -1850);
WIRE 16 3135 (1375 -325)(1375 325);
WIRE 16 3135 (1375 325)(2625 325);
WIRE 16 3135 (1375 -325)(2625 -325);
WIRE 16 3135 (2625 -325)(2625 325);
WIRE 16 3135 (1400 -225)(2600 -225);
WIRE 16 -1 (2525 -900)(3225 -900);
FORCEPROP 2 LAST SIG_NAME HP_LVC3_SCM_HSC_PWRGD
J 0
(2590 -890);
DISPLAY 0.638298 (2590 -890);
WIRE 16 -1 (3900 -825)(3900 -775);
WIRE 16 -1 (3425 -775)(3900 -775);
WIRE 16 -1 (3425 -1050)(3425 -775);
WIRE 16 -1 (2625 -1175)(2625 -1050);
WIRE 16 -1 (2625 -1050)(3425 -1050);
WIRE 16 -1 (2025 -1175)(2025 -1050);
WIRE 16 -1 (2025 -1050)(2625 -1050);
WIRE 16 -1 (1425 -1050)(1732 -1050);
WIRE 16 -1 (1732 -1050)(2025 -1050);
WIRE 16 -1 (1425 -1100)(1732 -1100);
WIRE 16 -1 (1732 -1100)(1732 -1050);
WIRE 16 -1 (1425 -1150)(1732 -1150);
WIRE 16 -1 (1732 -1150)(1732 -1100);
WIRE 16 -1 (1425 -1200)(1732 -1200);
WIRE 16 -1 (1732 -1200)(1732 -1150);
WIRE 16 -1 (1732 -1250)(1425 -1250);
WIRE 16 -1 (1732 -1250)(1732 -1200);
WIRE 16 -1 (1425 -1300)(1732 -1300);
WIRE 16 -1 (1732 -1300)(1732 -1250);
WIRE 16 -1 (1425 -1350)(1732 -1350);
WIRE 16 -1 (1732 -1350)(1732 -1300);
WIRE 16 -1 (1732 -1350)(1732 -1400);
WIRE 16 -1 (1425 -1400)(1732 -1400);
WIRE 16 -1 (3025 -1250)(3025 -1150);
WIRE 16 -1 (3025 -1150)(3550 -1150);
WIRE 16 -1 (3550 -1150)(3550 -1250);
WIRE 16 -1 (1425 -1600)(2625 -1600);
FORCEPROP 2 LAST SIG_NAME P12V_SCM_OV_FB
J 0
(1515 -1590);
DISPLAY 0.510638 (1515 -1590);
WIRE 16 -1 (2625 -1375)(2625 -1600);
WIRE 16 -1 (3025 -1600)(2625 -1600);
WIRE 16 -1 (3025 -1600)(3025 -1675);
WIRE 16 -1 (3025 -1450)(3025 -1600);
WIRE 16 -1 (1425 -1500)(2025 -1500);
FORCEPROP 2 LAST SIG_NAME P12V_SCM_AVIN_PD
J 0
(1515 -1490);
DISPLAY 0.510638 (1515 -1490);
WIRE 16 -1 (2025 -1500)(2175 -1500);
WIRE 16 -1 (2025 -1375)(2025 -1500);
WIRE 16 -1 (625 -1350)(300 -1350);
WIRE 16 -1 (-275 1960)(-275 2125);
WIRE 16 -1 (-275 1960)(-500 1960);
WIRE 16 -1 (-650 1960)(-500 1960);
WIRE 16 -1 (-650 2100)(-650 1960);
WIRE 16 -1 (-650 2400)(-650 2450);
WIRE 16 -1 (-650 2450)(-500 2450);
WIRE 16 -1 (-275 2450)(-500 2450);
WIRE 16 -1 (-275 2450)(-275 2325);
WIRE 16 -1 (-275 2450)(75 2450);
WIRE 16 -1 (75 2450)(75 2025);
WIRE 16 -1 (75 2450)(400 2450);
WIRE 16 -1 (400 2450)(400 2325);
WIRE 16 -1 (1175 2450)(400 2450);
WIRE 16 -1 (1175 2000)(1275 2000);
WIRE 16 -1 (1175 2450)(1175 2000);
WIRE 16 -1 (1175 2000)(1175 1950);
WIRE 16 -1 (1175 1950)(1275 1950);
WIRE 16 -1 (1175 1900)(1275 1900);
WIRE 16 -1 (1175 1950)(1175 1900);
WIRE 16 -1 (1175 1900)(1175 1850);
WIRE 16 -1 (1175 1850)(1275 1850);
WIRE 16 -1 (1175 1850)(1175 1800);
WIRE 16 -1 (1175 1800)(1275 1800);
WIRE 16 -1 (1175 1750)(1275 1750);
WIRE 16 -1 (1175 1800)(1175 1750);
WIRE 16 -1 (1175 1750)(1175 1700);
WIRE 16 -1 (1175 1700)(1275 1700);
WIRE 16 -1 (566 -1850)(625 -1850);
WIRE 16 -1 (150 -650)(150 -750);
WIRE 16 -1 (545 -650)(150 -650);
WIRE 16 -1 (545 -900)(625 -900);
WIRE 16 -1 (545 -650)(545 -900);
WIRE 16 -1 (545 -950)(545 -900);
WIRE 16 -1 (625 -950)(545 -950);
WIRE 16 -1 (545 -1000)(545 -950);
WIRE 16 -1 (625 -1000)(545 -1000);
WIRE 16 -1 (625 -1050)(545 -1050);
WIRE 16 -1 (545 -1050)(545 -1000);
WIRE 16 -1 (545 -1100)(545 -1050);
WIRE 16 -1 (625 -1100)(545 -1100);
WIRE 16 -1 (1650 -2225)(1650 -2405);
WIRE 16 -1 (3550 -2025)(3550 -1875);
WIRE 16 -1 (3025 -1875)(3025 -2025);
WIRE 16 -1 (925 850)(925 875);
WIRE 16 -1 (1250 850)(925 850);
WIRE 16 -1 (1250 1100)(1250 850);
WIRE 16 -1 (1275 1100)(1250 1100);
WIRE 16 -1 (2525 1025)(2525 900);
WIRE 16 -1 (2075 1200)(2300 1200);
WIRE 16 -1 (2400 900)(2525 900);
WIRE 16 -1 (2075 1100)(2250 1100);
WIRE 16 -1 (2300 900)(2400 900);
WIRE 16 -1 (2300 1200)(2300 900);
WIRE 16 -1 (2075 1050)(2200 1050);
WIRE 16 -1 (2300 900)(2250 900);
WIRE 16 -1 (2250 1100)(2250 900);
WIRE 16 -1 (2200 900)(2250 900);
WIRE 16 -1 (2200 1050)(2200 900);
WIRE 16 -1 (2150 900)(2200 900);
WIRE 16 -1 (2150 900)(2150 1000);
WIRE 16 -1 (2150 1000)(2075 1000);
WIRE 16 -1 (3500 2000)(3500 1850);
WIRE 16 -1 (3700 2000)(3500 2000);
WIRE 16 -1 (3925 2000)(3700 2000);
WIRE 16 -1 (3925 2000)(3925 1850);
WIRE 16 -1 (4200 2250)(4200 2325);
WIRE 16 -1 (3800 2250)(3800 2325);
WIRE 16 -1 (4200 2250)(3800 2250);
WIRE 16 -1 (3375 2250)(3375 2325);
WIRE 16 -1 (3800 2250)(3375 2250);
WIRE 16 -1 (2900 2250)(3375 2250);
WIRE 16 -1 (2900 2325)(2900 2250);
WIRE 16 -1 (4200 2525)(4200 2625);
WIRE 16 -1 (3800 2625)(3800 2525);
WIRE 16 -1 (4200 2625)(3800 2625);
WIRE 16 -1 (3375 2525)(3375 2625);
WIRE 16 -1 (3800 2625)(3375 2625);
WIRE 16 -1 (2900 2625)(2900 2575);
WIRE 16 -1 (3375 2625)(2900 2625);
WIRE 16 -1 (2695 2625)(2900 2625);
WIRE 16 -1 (2800 2000)(2800 1950);
WIRE 16 -1 (2695 2000)(2800 2000);
WIRE 16 -1 (2695 2625)(2695 2000);
WIRE 16 -1 (2475 1925)(2475 2000);
WIRE 16 -1 (2695 2000)(2475 2000);
WIRE 16 -1 (2075 2000)(2382 2000);
WIRE 16 -1 (2382 2000)(2475 2000);
WIRE 16 -1 (2075 1950)(2382 1950);
WIRE 16 -1 (2382 1950)(2382 2000);
WIRE 16 -1 (2075 1900)(2382 1900);
WIRE 16 -1 (2382 1900)(2382 1950);
WIRE 16 -1 (2075 1850)(2382 1850);
WIRE 16 -1 (2382 1850)(2382 1900);
WIRE 16 -1 (2382 1800)(2075 1800);
WIRE 16 -1 (2382 1800)(2382 1850);
WIRE 16 -1 (2075 1750)(2382 1750);
WIRE 16 -1 (2382 1750)(2382 1800);
WIRE 16 -1 (2382 1700)(2382 1750);
WIRE 16 -1 (2075 1700)(2382 1700);
WIRE 16 3135 (1400 -125)(2600 -125);
WIRE 16 -1 (3500 1400)(3325 1400);
WIRE 16 -1 (3500 1650)(3500 1400);
WIRE 16 -1 (4275 1400)(3500 1400);
FORCEPROP 2 LAST SIG_NAME P12V_SCM_FAULT_R_N
J 0
(3715 1410);
DISPLAY 0.574468 (3715 1410);
WIRE 16 -1 (1425 -900)(2275 -900);
FORCEPROP 2 LAST SIG_NAME HP_LVC3_SCM_HSC_PWRGD_R
J 0
(1540 -890);
DISPLAY 0.638298 (1540 -890);
WIRE 16 -1 (2275 -900)(2325 -900);
WIRE 16 -1 (2275 -750)(2275 -900);
WIRE 16 3135 (1750 300)(1750 -300);
WIRE 16 -1 (2350 -2300)(2600 -2300);
WIRE 16 -1 (2350 -1750)(1425 -1750);
FORCEPROP 2 LAST SIG_NAME P12V_SCM_FLTB_N
J 0
(1515 -1740);
DISPLAY 0.574468 (1515 -1740);
WIRE 16 -1 (2350 -1750)(2350 -2300);
WIRE 16 -1 (2375 -1750)(2350 -1750);
WIRE 16 -1 (1425 -1850)(1650 -1850);
WIRE 16 -1 (1650 -2025)(1650 -1850);
FORCEPROP 2 LAST SIG_NAME P12V_SCM_IMON
J 0
(1515 -1840);
DISPLAY 0.510638 (1515 -1840);
WIRE 16 -1 (1650 -1850)(2100 -1850);
WIRE 16 -1 (2100 -2025)(2100 -1850);
WIRE 16 -1 (-200 -1250)(625 -1250);
FORCEPROP 2 LAST SIG_NAME P12V_SCM_EN_R2
J 0
(115 -1240);
DISPLAY 0.510638 (115 -1240);
WIRE 16 -1 (-1125 -1550)(-1125 -1650);
WIRE 16 -1 (-1125 -1550)(625 -1550);
FORCEPROP 2 LAST SIG_NAME P12V_SCM_TIMER
J 0
(115 -1540);
DISPLAY 0.510638 (115 -1540);
WIRE 16 -1 (-675 -1650)(-675 -1725);
WIRE 16 -1 (-250 -1650)(-675 -1650);
WIRE 16 -1 (-250 -1650)(-250 -1750);
WIRE 16 -1 (625 -1650)(-250 -1650);
FORCEPROP 2 LAST SIG_NAME P12V_SCM_ISET
J 0
(140 -1640);
DISPLAY 0.510638 (140 -1640);
WIRE 16 -1 (225 -1750)(225 -1825);
WIRE 16 -1 (625 -1750)(225 -1750);
FORCEPROP 2 LAST SIG_NAME P12V_SCM_SS
J 0
(190 -1740);
DISPLAY 0.510638 (190 -1740);
WIRE 16 -1 (2075 1600)(2475 1600);
FORCEPROP 2 LAST SIG_NAME P12V_SCM_GATE
J 0
(2165 1610);
DISPLAY 0.510638 (2165 1610);
WIRE 16 -1 (2475 1725)(2475 1600);
WIRE 16 -1 (2800 1600)(2475 1600);
WIRE 16 -1 (2975 1600)(2800 1600);
WIRE 16 -1 (2800 1750)(2800 1600);
WIRE 16 -1 (-3325 875)(-3125 875);
FORCEPROP 2 LAST SIG_NAME P12V_SCM_EN
J 0
(-3110 885);
DISPLAY 0.574468 (-3110 885);
WIRE 16 -1 (-3125 1050)(-3125 875);
WIRE 16 -1 (-2725 875)(-3125 875);
WIRE 16 -1 (-3125 875)(-3125 475);
WIRE 16 -1 (-1350 -25)(-1350 475);
WIRE 16 -1 (-3125 475)(-1350 475);
WIRE 16 -1 (-775 475)(-1350 475);
WIRE 16 -1 (-775 475)(-775 -1250);
WIRE 16 -1 (-400 -1250)(-775 -1250);
WIRE 16 -1 (3925 1650)(3925 1500);
FORCEPROP 2 LAST SIG_NAME HP_LVC3_SCM_HSC_PWRGD
J 0
(3690 1510);
DISPLAY 0.574468 (3690 1510);
WIRE 16 -1 (3925 1500)(4275 1500);
WIRE 16 -1 (3250 1500)(3925 1500);
WIRE 16 -1 (2075 1400)(3125 1400);
FORCEPROP 2 LAST SIG_NAME P12V_SCM_FAULT_N
J 0
(2165 1410);
DISPLAY 0.574468 (2165 1410);
WIRE 16 -1 (2075 1500)(3050 1500);
FORCEPROP 2 LAST SIG_NAME P12V_SCM_PWRGD
J 0
(2165 1510);
DISPLAY 0.574468 (2165 1510);
WIRE 16 -1 (2525 1225)(2525 1300);
FORCEPROP 2 LAST SIG_NAME P12V_SCM_SENSE
J 0
(2165 1310);
DISPLAY 0.510638 (2165 1310);
WIRE 16 -1 (2075 1300)(2525 1300);
WIRE 16 3135 (1400 175)(2600 175);
WIRE 16 3135 (1400 75)(2600 75);
WIRE 16 -1 (725 1500)(1275 1500);
FORCEPROP 2 LAST SIG_NAME P12V_SCM_REG
J 0
(840 1510);
DISPLAY 0.510638 (840 1510);
WIRE 16 -1 (750 1600)(1275 1600);
FORCEPROP 2 LAST SIG_NAME P12V_SCM_VCC
J 0
(840 1610);
DISPLAY 0.510638 (840 1610);
WIRE 16 -1 (750 2025)(750 1600);
WIRE 16 -1 (400 2025)(400 1900);
WIRE 16 -1 (750 2025)(400 2025);
WIRE 16 -1 (400 2125)(400 2025);
WIRE 16 -1 (925 1200)(925 1075);
WIRE 16 -1 (1275 1200)(925 1200);
FORCEPROP 2 LAST SIG_NAME P12V_SCM_CB
J 0
(865 1210);
DISPLAY 0.510638 (865 1210);
WIRE 16 -1 (375 1300)(1275 1300);
FORCEPROP 2 LAST SIG_NAME P12V_SCM_OV
J 0
(865 1310);
DISPLAY 0.510638 (865 1310);
WIRE 16 -1 (375 1100)(375 1300);
WIRE 16 -1 (75 1100)(75 1075);
WIRE 16 -1 (75 1100)(375 1100);
WIRE 16 -1 (75 1150)(75 1100);
WIRE 16 -1 (75 1400)(75 1350);
WIRE 16 -1 (75 1400)(1275 1400);
FORCEPROP 2 LAST SIG_NAME P12V_SCM_UV
J 0
(865 1410);
DISPLAY 0.510638 (865 1410);
WIRE 16 -1 (75 1400)(75 1600);
WIRE 16 -1 (75 1825)(75 1600);
WIRE 16 -1 (-400 1600)(75 1600);
WIRE 16 3135 (2175 300)(2175 -300);
WIRE 16 -1 (3550 -1625)(3550 -1675);
WIRE 16 -1 (3550 -1450)(3550 -1625);
WIRE 16 -1 (4150 -1625)(3550 -1625);
FORCEPROP 2 LAST SIG_NAME P12V_SCM_AVIN_PD
J 0
(3665 -1615);
DISPLAY 0.510638 (3665 -1615);
WIRE 16 -1 (2800 -2300)(3500 -2300);
FORCEPROP 0 LAST VOLTAGE 0
J 0
(2940 -2263);
DISPLAY INVISIBLE (2940 -2263);
FORCEPROP 2 LAST SIG_NAME P12V_SCM_FAULT_R_N
J 0
(3015 -2290);
DISPLAY 0.574468 (3015 -2290);
WIRE 16 3135 (1400 -25)(2600 -25);
WIRE 16 -1 (-600 1600)(-1050 1600);
FORCEPROP 2 LAST SIG_NAME P12V_SCM_UV_R
J 0
(-985 1610);
DISPLAY 0.510638 (-985 1610);
WIRE 16 -1 (-1050 1475)(-1050 1600);
WIRE 16 -1 (-1725 1425)(-1725 1225);
WIRE 16 -1 (-1725 1225)(-1300 1225);
FORCEPROP 2 LAST SIG_NAME P12V_SCM_EN_G
J 0
(-1685 1235);
DISPLAY 0.510638 (-1685 1235);
WIRE 16 -1 (-1725 1125)(-1725 1225);
WIRE 16 -1 (-2525 875)(-1975 875);
FORCEPROP 2 LAST SIG_NAME P12V_SCM_EN_R
J 0
(-2360 885);
DISPLAY 0.510638 (-2360 885);
WIRE 16 -1 (-3525 875)(-4300 875);
FORCEPROP 2 LAST SIG_NAME VIRTUAL_RESEAT_FPGA_N
J 0
(-4310 885);
DISPLAY 0.808511 (-4310 885);
WIRE 16 2175 (-4575 3200)(-2872 3200);
WIRE 16 2175 (-2872 3200)(-2872 2300);
WIRE 16 2175 (-4575 3200)(-4575 2300);
WIRE 16 2175 (-4575 2300)(-2872 2300);
WIRE 16 -1 (-250 -1950)(-250 -2050);
FORCEPROP 2 LAST SIG_NAME P12V_SCM_ISET_R
J 0
(-235 -2015);
DISPLAY 0.510638 (-235 -2015);
WIRE 16 -1 (-2300 -225)(-1550 -225);
FORCEPROP 2 LAST SIG_NAME FM_SCM_PRSNT1_R_N
J 0
(-2135 -215);
DISPLAY 0.638298 (-2135 -215);
PAINT WHITE (-2135 -215);
WIRE 16 -1 (-3350 -100)(-3350 -225);
WIRE 16 -1 (-3350 -225)(-2500 -225);
FORCEPROP 2 LAST SIG_NAME FM_SCM_PRSNT1_N
J 0
(-3235 -215);
DISPLAY 0.638298 (-3235 -215);
PAINT WHITE (-3235 -215);
WIRE 16 -1 (-3575 -225)(-3350 -225);
DOT 1 (-3350 -225);
DOT 1 (-250 -1650);
DOT 1 (-3125 875);
DOT 1 (-1350 475);
DOT 1 (-1725 1225);
DOT 1 (-500 1960);
DOT 1 (-500 2450);
DOT 1 (-275 2450);
DOT 1 (150 -650);
DOT 1 (1650 -1850);
DOT 1 (1732 -1050);
DOT 1 (2100 -2405);
DOT 1 (3225 -2025);
DOT 1 (2350 -1750);
DOT 1 (3025 -1600);
DOT 1 (3550 -1625);
DOT 1 (3550 -1150);
DOT 1 (925 850);
DOT 1 (75 1100);
DOT 1 (75 1400);
DOT 1 (400 1500);
DOT 1 (75 1600);
DOT 1 (400 2025);
DOT 1 (1175 1750);
DOT 1 (1175 1800);
DOT 1 (1175 1850);
DOT 1 (1175 1950);
DOT 1 (1175 1900);
DOT 1 (1175 2000);
DOT 1 (75 2450);
DOT 1 (400 2450);
DOT 1 (2200 900);
DOT 1 (2250 900);
DOT 1 (2300 900);
DOT 1 (2400 900);
DOT 1 (2382 1800);
DOT 1 (2382 1750);
DOT 1 (2475 1600);
DOT 1 (2382 1850);
DOT 1 (2382 1950);
DOT 1 (2382 1900);
DOT 1 (2382 2000);
DOT 1 (2475 2000);
DOT 1 (2800 1600);
DOT 1 (2695 2000);
DOT 1 (3500 1400);
DOT 1 (3700 2000);
DOT 1 (2900 2625);
DOT 1 (3375 2250);
DOT 1 (3375 2625);
DOT 1 (3800 2250);
DOT 1 (3800 2625);
DOT 1 (4200 2250);
DOT 1 (4200 2625);
DOT 1 (3900 -775);
DOT 1 (2025 -1050);
DOT 1 (2625 -1050);
DOT 1 (545 -900);
DOT 1 (545 -950);
DOT 1 (545 -1000);
DOT 1 (545 -1050);
DOT 1 (1732 -1100);
DOT 1 (1732 -1150);
DOT 1 (1732 -1200);
DOT 1 (1732 -1250);
DOT 1 (1732 -1300);
DOT 1 (1732 -1350);
DOT 1 (300 -1450);
DOT 1 (2025 -1500);
DOT 1 (2625 -1600);
DOT 1 (2275 -900);
DOT 1 (3925 1500);
FORCENOTE
TDELAY: 6.29MS
(-1650 -2300) 0;
DISPLAY LEFT (-1650 -2300);
DISPLAY 1.021277 (-1650 -2300);
PAINT WHITE (-1650 -2300);
FORCENOTE
ENABLE:
(-1625 -1450) 0;
DISPLAY LEFT (-1625 -1450);
DISPLAY 1.021277 (-1625 -1450);
PAINT WHITE (-1625 -1450);
FORCENOTE
VTH>1.391V(HIGH)
(-1625 -1516) 0;
DISPLAY LEFT (-1625 -1516);
DISPLAY 1.021277 (-1625 -1516);
PAINT WHITE (-1625 -1516);
FORCENOTE
IMAX=4A
(-4525 2950) 0;
DISPLAY LEFT (-4525 2950);
DISPLAY 1.021277 (-4525 2950);
FORCENOTE
P12V_SCM_R
(-4525 3025) 0;
DISPLAY LEFT (-4525 3025);
DISPLAY 1.021277 (-4525 3025);
FORCENOTE
OCP=MAX*1.3=5.2A
(-4525 2875) 0;
DISPLAY LEFT (-4525 2875);
DISPLAY 1.021277 (-4525 2875);
FORCENOTE
DESIGN SPECIFICATION
(-4538 3119) 0;
DISPLAY LEFT (-4538 3119);
DISPLAY 1.170213 (-4538 3119);
FORCENOTE
20211116 MODIFY FOR GT
(-2125 3025) 0;
DISPLAY LEFT (-2125 3025);
DISPLAY 2.510638 (-2125 3025);
PAINT PINK (-2125 3025);
FORCENOTE
UVP: 10.17V
(-500 1350) 0;
DISPLAY LEFT (-500 1350);
DISPLAY 1.021277 (-500 1350);
PAINT WHITE (-500 1350);
FORCENOTE
OVP: 14.91V
(-500 1275) 0;
DISPLAY LEFT (-500 1275);
DISPLAY 1.021277 (-500 1275);
PAINT WHITE (-500 1275);
FORCENOTE
PR4010
(1450 -100) 0;
DISPLAY LEFT (1450 -100);
DISPLAY 1.021277 (1450 -100);
FORCENOTE
PR4014
(1450 -200) 0;
DISPLAY LEFT (1450 -200);
DISPLAY 1.021277 (1450 -200);
FORCENOTE
PR4009
(1450 0) 0;
DISPLAY LEFT (1450 0);
DISPLAY 1.021277 (1450 0);
FORCENOTE
POP
(1800 -300) 0;
DISPLAY LEFT (1800 -300);
DISPLAY 1.021277 (1800 -300);
FORCENOTE
POP
(1800 -200) 0;
DISPLAY LEFT (1800 -200);
DISPLAY 1.021277 (1800 -200);
FORCENOTE
POP
(1800 -100) 0;
DISPLAY LEFT (1800 -100);
DISPLAY 1.021277 (1800 -100);
FORCENOTE
DE-POP
(1800 0) 0;
DISPLAY LEFT (1800 0);
DISPLAY 1.021277 (1800 0);
FORCENOTE
POP
(2275 0) 0;
DISPLAY LEFT (2275 0);
DISPLAY 1.021277 (2275 0);
FORCENOTE
DE-POP
(2225 -200) 0;
DISPLAY LEFT (2225 -200);
DISPLAY 1.021277 (2225 -200);
FORCENOTE
PR4006
(1450 100) 0;
DISPLAY LEFT (1450 100);
DISPLAY 1.021277 (1450 100);
FORCENOTE
MP5025C/
(1775 250) 0;
DISPLAY LEFT (1775 250);
DISPLAY 1.021277 (1775 250);
FORCENOTE
PU299 OPTIONAL BOM
(1400 350) 0;
DISPLAY LEFT (1400 350);
DISPLAY 1.021277 (1400 350);
FORCENOTE
MP5022C
(1775 200) 0;
DISPLAY LEFT (1775 200);
DISPLAY 1.021277 (1775 200);
FORCENOTE
DE-POP
(1800 100) 0;
DISPLAY LEFT (1800 100);
DISPLAY 1.021277 (1800 100);
FORCENOTE
POP
(2275 100) 0;
DISPLAY LEFT (2275 100);
DISPLAY 1.021277 (2275 100);
FORCENOTE
MP5022A
(2225 200) 0;
DISPLAY LEFT (2225 200);
DISPLAY 1.021277 (2225 200);
FORCENOTE
MP5025A/
(2225 250) 0;
DISPLAY LEFT (2225 250);
DISPLAY 1.021277 (2225 250);
FORCENOTE
DE-POP
(2225 -100) 0;
DISPLAY LEFT (2225 -100);
DISPLAY 1.021277 (2225 -100);
FORCENOTE
START UP TIME:8.62MS
(-25 -2300) 0;
DISPLAY LEFT (-25 -2300);
DISPLAY 1.021277 (-25 -2300);
PAINT WHITE (-25 -2300);
FORCENOTE
VIMON(MAX)= 1.610V @ IOUT=5.35A
(300 -2625) 0;
DISPLAY LEFT (300 -2625);
DISPLAY 1.021277 (300 -2625);
PAINT WHITE (300 -2625);
FORCENOTE
TFAULT: 1.27MS
(-1650 -2225) 0;
DISPLAY LEFT (-1650 -2225);
DISPLAY 1.021277 (-1650 -2225);
PAINT WHITE (-1650 -2225);
FORCENOTE
VIMON(MAX)= 1.563V @ IOUT=5.34A
(1175 450) 0;
DISPLAY LEFT (1175 450);
DISPLAY 1.021277 (1175 450);
PAINT WHITE (1175 450);
FORCENOTE
START UP TIME:8.21MS
(3550 1275) 0;
DISPLAY LEFT (3550 1275);
DISPLAY 1.021277 (3550 1275);
PAINT WHITE (3550 1275);
FORCENOTE
DE-POP
(2225 -300) 0;
DISPLAY LEFT (2225 -300);
DISPLAY 1.021277 (2225 -300);
FORCENOTE
PC2239
(1450 -300) 0;
DISPLAY LEFT (1450 -300);
DISPLAY 1.021277 (1450 -300);
QUIT
